G04 ================== begin FILE IDENTIFICATION RECORD ==================*
G04 Layout Name:  D:/<user>/Wistron_project/16318-2/gbr/16318-2.brd*
G04 Film Name:    L2GND*
G04 File Format:  Gerber RS274X*
G04 File Origin:  Cadence Allegro 16.5-S056*
G04 Origin Date:  Mon Aug 07 11:09:38 2017*
G04 *
G04 Layer:  VIA CLASS/L2GND*
G04 Layer:  PIN/L2GND*
G04 Layer:  ETCH/L2GND*
G04 Layer:  DRAWING FORMAT/LAYER_PCB_STORY*
G04 Layer:  DRAWING FORMAT/LAYER_L2GND*
G04 *
G04 Offset:    (0.00 0.00)*
G04 Mirror:    No*
G04 Mode:      Negative*
G04 Rotation:  0*
G04 FullContactRelief:  No*
G04 UndefLineWidth:     6.00*
G04 ================== end FILE IDENTIFICATION RECORD ====================*
%FSLAX35Y35*MOIN*%
%IR0*IPPOS*OFA0.00000B0.00000*MIA0B0*SFA1.00000B1.00000*%
%AMMACRO12*
4,1,13,.02632,.01218,
.028035,.007425,
.028899,.002443,
.028884,-.002612,
.027991,-.007588,
.02632,-.01218,
.03005,-.01591,
.032356,-.01045,
.033679,-.004673,
.033979,.001247,
.033246,.007128,
.031504,.012793,
.03005,.01591,
.02632,.01218,
0.0*
4,1,13,.01218,-.02632,
.007425,-.028035,
.002443,-.028899,
-.002612,-.028884,
-.007588,-.027991,
-.01218,-.02632,
-.01591,-.03005,
-.01045,-.032356,
-.004673,-.033679,
.001247,-.033979,
.007128,-.033246,
.012793,-.031504,
.01591,-.03005,
.01218,-.02632,
0.0*
4,1,13,-.02632,-.01218,
-.028035,-.007425,
-.028899,-.002443,
-.028884,.002612,
-.027991,.007588,
-.02632,.01218,
-.03005,.01591,
-.032356,.01045,
-.033679,.004673,
-.033979,-.001247,
-.033246,-.007128,
-.031504,-.012793,
-.03005,-.01591,
-.02632,-.01218,
0.0*
4,1,13,-.01218,.02632,
-.007425,.028035,
-.002443,.028899,
.002612,.028884,
.007588,.027991,
.01218,.02632,
.01591,.03005,
.01045,.032356,
.004673,.033679,
-.001247,.033979,
-.007128,.033246,
-.012793,.031504,
-.01591,.03005,
-.01218,.02632,
0.0*
%
%ADD12MACRO12*%
%ADD26O,.072X.123*%
%ADD14C,.03*%
%ADD38C,.051*%
%ADD25C,.06*%
%ADD32C,.043*%
%ADD29C,.062*%
%ADD35C,.063*%
%ADD20C,.036*%
%ADD23C,.028*%
%ADD30C,.056*%
%ADD28C,.076*%
%ADD11C,.068*%
%AMMACRO19*
4,1,15,.00398,.00044,
.003999,.000208,
.004004,-.000025,
.003996,-.000258,
.00398,-.00044,
.00483,-.00129,
.004897,-.001007,
.004947,-.000721,
.004981,-.000432,
.004997,-.000141,
.004997,.000149,
.00498,.00044,
.004946,.000729,
.004895,.001015,
.00483,.00129,
.00398,.00044,
90.*
4,1,15,.00044,-.00398,
.000208,-.003999,
-.000025,-.004004,
-.000258,-.003996,
-.00044,-.00398,
-.00129,-.00483,
-.001007,-.004897,
-.000721,-.004947,
-.000432,-.004981,
-.000141,-.004997,
.000149,-.004997,
.00044,-.00498,
.000729,-.004946,
.001015,-.004895,
.00129,-.00483,
.00044,-.00398,
90.*
4,1,15,-.00398,-.00044,
-.003999,-.000208,
-.004004,.000025,
-.003996,.000258,
-.00398,.00044,
-.00483,.00129,
-.004897,.001007,
-.004947,.000721,
-.004981,.000432,
-.004997,.000141,
-.004997,-.000149,
-.00498,-.00044,
-.004946,-.000729,
-.004895,-.001015,
-.00483,-.00129,
-.00398,-.00044,
90.*
4,1,15,-.00044,.00398,
-.000208,.003999,
.000025,.004004,
.000258,.003996,
.00044,.00398,
.00129,.00483,
.001007,.004897,
.000721,.004947,
.000432,.004981,
.000141,.004997,
-.000149,.004997,
-.00044,.00498,
-.000729,.004946,
-.001015,.004895,
-.00129,.00483,
-.00044,.00398,
90.*
%
%ADD19MACRO19*%
%AMMACRO10*
4,1,15,.00398,.00044,
.003999,.000208,
.004004,-.000025,
.003996,-.000258,
.00398,-.00044,
.00483,-.00129,
.004897,-.001007,
.004947,-.000721,
.004981,-.000432,
.004997,-.000141,
.004997,.000149,
.00498,.00044,
.004946,.000729,
.004895,.001015,
.00483,.00129,
.00398,.00044,
0.0*
4,1,15,.00044,-.00398,
.000208,-.003999,
-.000025,-.004004,
-.000258,-.003996,
-.00044,-.00398,
-.00129,-.00483,
-.001007,-.004897,
-.000721,-.004947,
-.000432,-.004981,
-.000141,-.004997,
.000149,-.004997,
.00044,-.00498,
.000729,-.004946,
.001015,-.004895,
.00129,-.00483,
.00044,-.00398,
0.0*
4,1,15,-.00398,-.00044,
-.003999,-.000208,
-.004004,.000025,
-.003996,.000258,
-.00398,.00044,
-.00483,.00129,
-.004897,.001007,
-.004947,.000721,
-.004981,.000432,
-.004997,.000141,
-.004997,-.000149,
-.00498,-.00044,
-.004946,-.000729,
-.004895,-.001015,
-.00483,-.00129,
-.00398,-.00044,
0.0*
4,1,15,-.00044,.00398,
-.000208,.003999,
.000025,.004004,
.000258,.003996,
.00044,.00398,
.00129,.00483,
.001007,.004897,
.000721,.004947,
.000432,.004981,
.000141,.004997,
-.000149,.004997,
-.00044,.00498,
-.000729,.004946,
-.001015,.004895,
-.00129,.00483,
-.00044,.00398,
0.0*
%
%ADD10MACRO10*%
%ADD34C,.122*%
%ADD13C,.114*%
%ADD33C,.125*%
%ADD37C,.127*%
%ADD24C,.208*%
%ADD16O,.296X.162*%
%ADD39C,.147*%
%ADD27O,.072X.096*%
%ADD22C,.158*%
%ADD15C,.178*%
%ADD21C,.198*%
%AMMACRO41*
4,1,15,.00398,.00044,
.003999,.000208,
.004004,-.000025,
.003996,-.000258,
.00398,-.00044,
.00483,-.00129,
.004897,-.001007,
.004947,-.000721,
.004981,-.000432,
.004997,-.000141,
.004997,.000149,
.00498,.00044,
.004946,.000729,
.004895,.001015,
.00483,.00129,
.00398,.00044,
315.*
4,1,15,.00044,-.00398,
.000208,-.003999,
-.000025,-.004004,
-.000258,-.003996,
-.00044,-.00398,
-.00129,-.00483,
-.001007,-.004897,
-.000721,-.004947,
-.000432,-.004981,
-.000141,-.004997,
.000149,-.004997,
.00044,-.00498,
.000729,-.004946,
.001015,-.004895,
.00129,-.00483,
.00044,-.00398,
315.*
4,1,15,-.00398,-.00044,
-.003999,-.000208,
-.004004,.000025,
-.003996,.000258,
-.00398,.00044,
-.00483,.00129,
-.004897,.001007,
-.004947,.000721,
-.004981,.000432,
-.004997,.000141,
-.004997,-.000149,
-.00498,-.00044,
-.004946,-.000729,
-.004895,-.001015,
-.00483,-.00129,
-.00398,-.00044,
315.*
4,1,15,-.00044,.00398,
-.000208,.003999,
.000025,.004004,
.000258,.003996,
.00044,.00398,
.00129,.00483,
.001007,.004897,
.000721,.004947,
.000432,.004981,
.000141,.004997,
-.000149,.004997,
-.00044,.00498,
-.000729,.004946,
-.001015,.004895,
-.00129,.00483,
-.00044,.00398,
315.*
%
%ADD41MACRO41*%
%AMMACRO40*
4,1,15,.00398,.00044,
.003999,.000208,
.004004,-.000025,
.003996,-.000258,
.00398,-.00044,
.00483,-.00129,
.004897,-.001007,
.004947,-.000721,
.004981,-.000432,
.004997,-.000141,
.004997,.000149,
.00498,.00044,
.004946,.000729,
.004895,.001015,
.00483,.00129,
.00398,.00044,
135.*
4,1,15,.00044,-.00398,
.000208,-.003999,
-.000025,-.004004,
-.000258,-.003996,
-.00044,-.00398,
-.00129,-.00483,
-.001007,-.004897,
-.000721,-.004947,
-.000432,-.004981,
-.000141,-.004997,
.000149,-.004997,
.00044,-.00498,
.000729,-.004946,
.001015,-.004895,
.00129,-.00483,
.00044,-.00398,
135.*
4,1,15,-.00398,-.00044,
-.003999,-.000208,
-.004004,.000025,
-.003996,.000258,
-.00398,.00044,
-.00483,.00129,
-.004897,.001007,
-.004947,.000721,
-.004981,.000432,
-.004997,.000141,
-.004997,-.000149,
-.00498,-.00044,
-.004946,-.000729,
-.004895,-.001015,
-.00483,-.00129,
-.00398,-.00044,
135.*
4,1,15,-.00044,.00398,
-.000208,.003999,
.000025,.004004,
.000258,.003996,
.00044,.00398,
.00129,.00483,
.001007,.004897,
.000721,.004947,
.000432,.004981,
.000141,.004997,
-.000149,.004997,
-.00044,.00498,
-.000729,.004946,
-.001015,.004895,
-.00129,.00483,
-.00044,.00398,
135.*
%
%ADD40MACRO40*%
%AMMACRO18*
4,1,15,.00398,.00044,
.003999,.000208,
.004004,-.000025,
.003996,-.000258,
.00398,-.00044,
.00483,-.00129,
.004897,-.001007,
.004947,-.000721,
.004981,-.000432,
.004997,-.000141,
.004997,.000149,
.00498,.00044,
.004946,.000729,
.004895,.001015,
.00483,.00129,
.00398,.00044,
270.*
4,1,15,.00044,-.00398,
.000208,-.003999,
-.000025,-.004004,
-.000258,-.003996,
-.00044,-.00398,
-.00129,-.00483,
-.001007,-.004897,
-.000721,-.004947,
-.000432,-.004981,
-.000141,-.004997,
.000149,-.004997,
.00044,-.00498,
.000729,-.004946,
.001015,-.004895,
.00129,-.00483,
.00044,-.00398,
270.*
4,1,15,-.00398,-.00044,
-.003999,-.000208,
-.004004,.000025,
-.003996,.000258,
-.00398,.00044,
-.00483,.00129,
-.004897,.001007,
-.004947,.000721,
-.004981,.000432,
-.004997,.000141,
-.004997,-.000149,
-.00498,-.00044,
-.004946,-.000729,
-.004895,-.001015,
-.00483,-.00129,
-.00398,-.00044,
270.*
4,1,15,-.00044,.00398,
-.000208,.003999,
.000025,.004004,
.000258,.003996,
.00044,.00398,
.00129,.00483,
.001007,.004897,
.000721,.004947,
.000432,.004981,
.000141,.004997,
-.000149,.004997,
-.00044,.00498,
-.000729,.004946,
-.001015,.004895,
-.00129,.00483,
-.00044,.00398,
270.*
%
%ADD18MACRO18*%
%AMMACRO17*
4,1,15,.00398,.00044,
.003999,.000208,
.004004,-.000025,
.003996,-.000258,
.00398,-.00044,
.00483,-.00129,
.004897,-.001007,
.004947,-.000721,
.004981,-.000432,
.004997,-.000141,
.004997,.000149,
.00498,.00044,
.004946,.000729,
.004895,.001015,
.00483,.00129,
.00398,.00044,
180.*
4,1,15,.00044,-.00398,
.000208,-.003999,
-.000025,-.004004,
-.000258,-.003996,
-.00044,-.00398,
-.00129,-.00483,
-.001007,-.004897,
-.000721,-.004947,
-.000432,-.004981,
-.000141,-.004997,
.000149,-.004997,
.00044,-.00498,
.000729,-.004946,
.001015,-.004895,
.00129,-.00483,
.00044,-.00398,
180.*
4,1,15,-.00398,-.00044,
-.003999,-.000208,
-.004004,.000025,
-.003996,.000258,
-.00398,.00044,
-.00483,.00129,
-.004897,.001007,
-.004947,.000721,
-.004981,.000432,
-.004997,.000141,
-.004997,-.000149,
-.00498,-.00044,
-.004946,-.000729,
-.004895,-.001015,
-.00483,-.00129,
-.00398,-.00044,
180.*
4,1,15,-.00044,.00398,
-.000208,.003999,
.000025,.004004,
.000258,.003996,
.00044,.00398,
.00129,.00483,
.001007,.004897,
.000721,.004947,
.000432,.004981,
.000141,.004997,
-.000149,.004997,
-.00044,.00498,
-.000729,.004946,
-.001015,.004895,
-.00129,.00483,
-.00044,.00398,
180.*
%
%ADD17MACRO17*%
%AMMACRO36*
4,1,13,.02442,.01028,
.025834,.005883,
.026463,.001308,
.026288,-.003307,
.025315,-.007822,
.02442,-.01028,
.02819,-.01405,
.030201,-.008941,
.031295,-.003561,
.031438,.001927,
.030626,.007357,
.028883,.012564,
.02819,.01405,
.02442,.01028,
0.0*
4,1,13,.01028,-.02442,
.005883,-.025834,
.001308,-.026463,
-.003307,-.026288,
-.007822,-.025315,
-.01028,-.02442,
-.01405,-.02819,
-.008941,-.030201,
-.003561,-.031295,
.001927,-.031438,
.007357,-.030626,
.012564,-.028883,
.01405,-.02819,
.01028,-.02442,
0.0*
4,1,13,-.02442,-.01028,
-.025834,-.005883,
-.026463,-.001308,
-.026288,.003307,
-.025315,.007822,
-.02442,.01028,
-.02819,.01405,
-.030201,.008941,
-.031295,.003561,
-.031438,-.001927,
-.030626,-.007357,
-.028883,-.012564,
-.02819,-.01405,
-.02442,-.01028,
0.0*
4,1,13,-.01028,.02442,
-.005883,.025834,
-.001308,.026463,
.003307,.026288,
.007822,.025315,
.01028,.02442,
.01405,.02819,
.008941,.030201,
.003561,.031295,
-.001927,.031438,
-.007357,.030626,
-.012564,.028883,
-.01405,.02819,
-.01028,.02442,
0.0*
%
%ADD36MACRO36*%
%AMMACRO31*
4,1,19,.02172,.00757,
.022123,.006294,
.022452,.004997,
.022705,.003683,
.02288,.002357,
.022979,.001023,
.022999,-.000315,
.022942,-.001652,
.022807,-.002983,
.022595,-.004304,
.022307,-.005611,
.021943,-.006898,
.02172,-.00757,
.02556,-.01142,
.027155,-.006808,
.027924,-.001989,
.027846,.00289,
.026921,.007681,
.02556,.01142,
.02172,.00757,
0.0*
4,1,19,.00757,-.02172,
.006294,-.022123,
.004997,-.022452,
.003683,-.022705,
.002357,-.02288,
.001023,-.022979,
-.000315,-.022999,
-.001652,-.022942,
-.002983,-.022807,
-.004304,-.022595,
-.005611,-.022307,
-.006898,-.021943,
-.00757,-.02172,
-.01142,-.02556,
-.006808,-.027155,
-.001989,-.027924,
.00289,-.027846,
.007681,-.026921,
.01142,-.02556,
.00757,-.02172,
0.0*
4,1,19,-.02172,-.00757,
-.022123,-.006294,
-.022452,-.004997,
-.022705,-.003683,
-.02288,-.002357,
-.022979,-.001023,
-.022999,.000315,
-.022942,.001652,
-.022807,.002983,
-.022595,.004304,
-.022307,.005611,
-.021943,.006898,
-.02172,.00757,
-.02556,.01142,
-.027155,.006808,
-.027924,.001989,
-.027846,-.00289,
-.026921,-.007681,
-.02556,-.01142,
-.02172,-.00757,
0.0*
4,1,19,-.00757,.02172,
-.006294,.022123,
-.004997,.022452,
-.003683,.022705,
-.002357,.02288,
-.001023,.022979,
.000315,.022999,
.001652,.022942,
.002983,.022807,
.004304,.022595,
.005611,.022307,
.006898,.021943,
.00757,.02172,
.01142,.02556,
.006808,.027155,
.001989,.027924,
-.00289,.027846,
-.007681,.026921,
-.01142,.02556,
-.00757,.02172,
0.0*
%
%ADD31MACRO31*%
%ADD42C,.02*%
%ADD43C,.006*%
%ADD52C,.07204*%
%ADD51C,.05604*%
%ADD53C,.05804*%
%ADD46C,.11004*%
%ADD54C,.12104*%
%ADD55C,.11804*%
%ADD49C,.15404*%
%ADD44O,.29202X.15802*%
%ADD58R,.08104X.05152*%
%ADD56C,.23626*%
%ADD45O,.29204X.15804*%
%ADD59R,.08104X.05154*%
%ADD57C,.2369*%
%ADD50C,.2964*%
%ADD47C,.37554*%
%ADD48C,.37566*%
G75*
%LPD*%
G75*
G36*
G01X-6000Y-6000D02*
X931197D01*
Y769780D01*
X-6000D01*
Y-6000D01*
G37*
%LPC*%
G75*
G36*
G01X903913Y760260D02*
X922094Y723897D01*
G02X922193Y723480I-834J-418D01*
G01Y3937D01*
G02X921260Y3004I-933J0D01*
G01X291457D01*
G02X290524Y3937I0J933D01*
G01Y429331D01*
G03X283583Y436272I-6941J0D01*
G01X124134D01*
G03X117193Y429331I0J-6941D01*
G01Y3937D01*
G02X116260Y3004I-933J0D01*
G01X3937D01*
G02X3004Y3937I0J933D01*
G01Y723480D01*
G02X3103Y723897I933J-1D01*
G01X21284Y760260D01*
G02X22118Y760776I835J-417D01*
G01X386150D01*
G02X386984Y760260I-1J-933D01*
G01X405165Y723897D01*
G02X405264Y723480I-834J-418D01*
G01Y188976D01*
G03X414199Y185972I4973J0D01*
G01X562179D01*
G03X571114Y188976I3962J3004D01*
G01Y723480D01*
G02X571213Y723897I933J-1D01*
G01X589394Y760260D01*
G02X590228Y760776I835J-417D01*
G01X903079D01*
G02X903913Y760260I-1J-933D01*
G37*
%LPD*%
G75*
G36*
G01X796849Y298753D02*
G02Y295733I0J-1510D01*
G01X793699D01*
G02X793700Y298753I1J1510D01*
G01X796849D01*
G37*
G36*
G01X817518Y266198D02*
G02X817316Y266400I0J202D01*
G01Y267200D01*
G02X817518Y267402I202J0D01*
G01X820718D01*
G02X820920Y267200I0J-202D01*
G01Y266400D01*
G02X820718Y266198I-202J0D01*
G01X817518D01*
G37*
G36*
G01Y268398D02*
G02X817316Y268600I0J202D01*
G01Y269400D01*
G02X817518Y269602I202J0D01*
G01X820718D01*
G02X820920Y269400I0J-202D01*
G01Y268600D01*
G02X820718Y268398I-202J0D01*
G01X817518D01*
G37*
G36*
G01Y272798D02*
G02X817316Y273000I0J202D01*
G01Y273800D01*
G02X817518Y274002I202J0D01*
G01X820718D01*
G02X820920Y273800I0J-202D01*
G01Y273000D01*
G02X820718Y272798I-202J0D01*
G01X817518D01*
G37*
G36*
G01Y274998D02*
G02X817316Y275200I0J202D01*
G01Y276000D01*
G02X817518Y276202I202J0D01*
G01X820718D01*
G02X820920Y276000I0J-202D01*
G01Y275200D01*
G02X820718Y274998I-202J0D01*
G01X817518D01*
G37*
G36*
G01Y279398D02*
G02X817316Y279600I0J202D01*
G01Y280400D01*
G02X817518Y280602I202J0D01*
G01X820718D01*
G02X820920Y280400I0J-202D01*
G01Y279600D01*
G02X820718Y279398I-202J0D01*
G01X817518D01*
G37*
G36*
G01Y281598D02*
G02X817316Y281800I0J202D01*
G01Y282600D01*
G02X817518Y282802I202J0D01*
G01X820718D01*
G02X820920Y282600I0J-202D01*
G01Y281800D01*
G02X820718Y281598I-202J0D01*
G01X817518D01*
G37*
G36*
G01Y285998D02*
G02X817316Y286200I0J202D01*
G01Y287000D01*
G02X817518Y287202I202J0D01*
G01X820718D01*
G02X820920Y287000I0J-202D01*
G01Y286200D01*
G02X820718Y285998I-202J0D01*
G01X817518D01*
G37*
G36*
G01Y288198D02*
G02X817316Y288400I0J202D01*
G01Y289200D01*
G02X817518Y289402I202J0D01*
G01X820718D01*
G02X820920Y289200I0J-202D01*
G01Y288400D01*
G02X820718Y288198I-202J0D01*
G01X817518D01*
G37*
G36*
G01Y292598D02*
G02X817316Y292800I0J202D01*
G01Y293600D01*
G02X817518Y293802I202J0D01*
G01X820718D01*
G02X820920Y293600I0J-202D01*
G01Y292800D01*
G02X820718Y292598I-202J0D01*
G01X817518D01*
G37*
G36*
G01Y294798D02*
G02X817316Y295000I0J202D01*
G01Y295800D01*
G02X817518Y296002I202J0D01*
G01X820718D01*
G02X820920Y295800I0J-202D01*
G01Y295000D01*
G02X820718Y294798I-202J0D01*
G01X817518D01*
G37*
G36*
G01Y299198D02*
G02X817316Y299400I0J202D01*
G01Y300200D01*
G02X817518Y300402I202J0D01*
G01X820718D01*
G02X820920Y300200I0J-202D01*
G01Y299400D01*
G02X820718Y299198I-202J0D01*
G01X817518D01*
G37*
G36*
G01Y301398D02*
G02X817316Y301600I0J202D01*
G01Y302400D01*
G02X817518Y302602I202J0D01*
G01X820718D01*
G02X820920Y302400I0J-202D01*
G01Y301600D01*
G02X820718Y301398I-202J0D01*
G01X817518D01*
G37*
G36*
G01Y252998D02*
G02X817316Y253200I0J202D01*
G01Y254000D01*
G02X817518Y254202I202J0D01*
G01X820718D01*
G02X820920Y254000I0J-202D01*
G01Y253200D01*
G02X820718Y252998I-202J0D01*
G01X817518D01*
G37*
G36*
G01Y255198D02*
G02X817316Y255400I0J202D01*
G01Y256200D01*
G02X817518Y256402I202J0D01*
G01X820718D01*
G02X820920Y256200I0J-202D01*
G01Y255400D01*
G02X820718Y255198I-202J0D01*
G01X817518D01*
G37*
G36*
G01Y259598D02*
G02X817316Y259800I0J202D01*
G01Y260600D01*
G02X817518Y260802I202J0D01*
G01X820718D01*
G02X820920Y260600I0J-202D01*
G01Y259800D01*
G02X820718Y259598I-202J0D01*
G01X817518D01*
G37*
G36*
G01Y261798D02*
G02X817316Y262000I0J202D01*
G01Y262800D01*
G02X817518Y263002I202J0D01*
G01X820718D01*
G02X820920Y262800I0J-202D01*
G01Y262000D01*
G02X820718Y261798I-202J0D01*
G01X817518D01*
G37*
G36*
G01X703980Y104192D02*
G02X707438Y106044I1729J926D01*
G01X710371Y100567D01*
X710372Y100565D01*
G02X706932Y98680I-1711J-959D01*
G01X703980Y104192D01*
G37*
G36*
G01X712838Y104191D02*
G02X716296Y106045I1729J927D01*
G01X719230Y100567D01*
X719231Y100565D01*
G02X715791Y98679I-1711J-959D01*
G01X712838Y104191D01*
G37*
G36*
G01X336094Y334271D02*
G02X333070I-1512J0D01*
G01Y337772D01*
G02X336094Y337771I1512J-1D01*
G01Y334271D01*
G37*
G36*
G01X305778Y340592D02*
G02X302756I-1511J0D01*
G01Y344093D01*
G02X305778Y344092I1511J-1D01*
G01Y340592D01*
G37*
G36*
G01X309078Y353192D02*
G02X306056I-1511J0D01*
G01Y356693D01*
G02X309078Y356692I1511J-1D01*
G01Y353192D01*
G37*
G36*
G01X305778Y365792D02*
G02X302756I-1511J0D01*
G01Y369293D01*
G02X305778Y369292I1511J-1D01*
G01Y365792D01*
G37*
G36*
G01X326670Y350371D02*
G02X329694I1512J0D01*
G01Y346870D01*
G02X326670Y346871I-1512J1D01*
G01Y350371D01*
G37*
G36*
G01X336094Y359474D02*
G02X333070I-1512J0D01*
G01Y362975D01*
G02X336094Y362974I1512J-1D01*
G01Y359474D01*
G37*
G36*
G01X329694Y372018D02*
G02X326670I-1512J0D01*
G01Y375519D01*
G02X329694Y375518I1512J-1D01*
G01Y372018D01*
G37*
G36*
G01X305778Y315392D02*
G02X302756I-1511J0D01*
G01Y318893D01*
G02X305778Y318892I1511J-1D01*
G01Y315392D01*
G37*
G36*
G01X309078Y277592D02*
G02X306056I-1511J0D01*
G01Y281093D01*
G02X309078Y281092I1511J-1D01*
G01Y277592D01*
G37*
G36*
G01X305778Y290192D02*
G02X302756I-1511J0D01*
G01Y293693D01*
G02X305778Y293692I1511J-1D01*
G01Y290192D01*
G37*
G36*
G01X333070Y287284D02*
G02X336094I1512J0D01*
G01Y283783D01*
G02X333070Y283784I-1512J1D01*
G01Y287284D01*
G37*
G36*
G01X309078Y302792D02*
G02X306056I-1511J0D01*
G01Y306293D01*
G02X309078Y306292I1511J-1D01*
G01Y302792D01*
G37*
G36*
G01X329694Y296477D02*
G02X326670I-1512J0D01*
G01Y299978D01*
G02X329694Y299977I1512J-1D01*
G01Y296477D01*
G37*
G36*
G01X336094Y309074D02*
G02X333070I-1512J0D01*
G01Y312575D01*
G02X336094Y312574I1512J-1D01*
G01Y309074D01*
G37*
G36*
G01X329694Y321674D02*
G02X326670I-1512J0D01*
G01Y325175D01*
G02X329694Y325174I1512J-1D01*
G01Y321674D01*
G37*
G36*
G01X309078Y328092D02*
G02X306056I-1511J0D01*
G01Y331593D01*
G02X309078Y331592I1511J-1D01*
G01Y328092D01*
G37*
G36*
G01X302720Y268548D02*
G02X305742I1511J0D01*
G01Y265047D01*
G02X302720Y265048I-1511J1D01*
G01Y268548D01*
G37*
G36*
G01X781670Y347206D02*
X781669Y347207D01*
X779234Y349642D01*
X779232Y349644D01*
G02X781330Y351794I1031J1093D01*
G01X783794Y349330D01*
G02X781670Y347206I-1057J-1067D01*
G37*
G36*
G01X764148Y351494D02*
X766612Y349030D01*
G02X764488Y346906I-1057J-1067D01*
G01X764487Y346907D01*
X762052Y349342D01*
X762050Y349344D01*
G02X764148Y351494I1031J1093D01*
G37*
G36*
G01X753430Y344794D02*
X755894Y342330D01*
G02X753770Y340206I-1057J-1067D01*
G01X753769Y340207D01*
X751334Y342642D01*
X751332Y342644D01*
G02X753430Y344794I1031J1093D01*
G37*
G36*
G01X793570Y335406D02*
X793569Y335407D01*
X791134Y337842D01*
X791132Y337844D01*
G02X793230Y339994I1031J1093D01*
G01X795694Y337530D01*
G02X793570Y335406I-1057J-1067D01*
G37*
G36*
G01X776248Y339494D02*
X778712Y337030D01*
G02X776588Y334906I-1057J-1067D01*
G01X776587Y334907D01*
X774152Y337342D01*
X774150Y337344D01*
G02X776248Y339494I1031J1093D01*
G37*
G36*
G01X803770Y333106D02*
X803769Y333107D01*
X801334Y335542D01*
X801332Y335544D01*
G02X803430Y337694I1031J1093D01*
G01X805894Y335230D01*
G02X803770Y333106I-1057J-1067D01*
G37*
G36*
G01X747330Y333794D02*
X749794Y331330D01*
G02X747670Y329206I-1057J-1067D01*
G01X747669Y329207D01*
X745234Y331642D01*
X745232Y331644D01*
G02X747330Y333794I1031J1093D01*
G37*
G36*
G01X765370Y328306D02*
X765369Y328307D01*
X762934Y330742D01*
X762932Y330744D01*
G02X765030Y332894I1031J1093D01*
G01X767494Y330430D01*
G02X765370Y328306I-1057J-1067D01*
G37*
G36*
G01X849476Y314648D02*
X849477Y314647D01*
X852620Y311503D01*
X852622Y311501D01*
G02X850524Y309352I-1031J-1092D01*
G01X847352Y312524D01*
G02X849476Y314648I1057J1067D01*
G37*
G36*
G01X853976Y299148D02*
X853977Y299147D01*
X857120Y296003D01*
X857122Y296001D01*
G02X855024Y293852I-1031J-1092D01*
G01X851852Y297024D01*
G02X853976Y299148I1057J1067D01*
G37*
G36*
G01X847976Y293148D02*
X847977Y293147D01*
X851120Y290003D01*
X851122Y290001D01*
G02X849024Y287852I-1031J-1092D01*
G01X845852Y291024D01*
G02X847976Y293148I1057J1067D01*
G37*
G36*
G01X842476Y287648D02*
X842477Y287647D01*
X845620Y284503D01*
X845622Y284501D01*
G02X843524Y282352I-1031J-1092D01*
G01X840352Y285524D01*
G02X842476Y287648I1057J1067D01*
G37*
G36*
G01X844476Y274648D02*
X844477Y274647D01*
X847620Y271503D01*
X847622Y271501D01*
G02X845524Y269352I-1031J-1092D01*
G01X842352Y272524D01*
G02X844476Y274648I1057J1067D01*
G37*
G36*
G01X838476Y268848D02*
X838477Y268847D01*
X841620Y265703D01*
X841622Y265701D01*
G02X839524Y263552I-1031J-1092D01*
G01X836352Y266724D01*
G02X838476Y268848I1057J1067D01*
G37*
G36*
G01X832676Y262348D02*
X832677Y262347D01*
X835820Y259203D01*
X835822Y259201D01*
G02X833724Y257052I-1031J-1092D01*
G01X830552Y260224D01*
G02X832676Y262348I1057J1067D01*
G37*
G36*
G01X832012Y252729D02*
X832013Y252728D01*
X835156Y249584D01*
X835158Y249582D01*
G02X833060Y247433I-1031J-1092D01*
G01X829888Y250605D01*
G02X832012Y252729I1057J1067D01*
G37*
G36*
G01X551124Y149798D02*
Y145478D01*
X551132Y145450D01*
G02X547292I-1920J-568D01*
G01X547300Y145478D01*
Y149798D01*
X547292Y149826D01*
G02X551132I1920J568D01*
G01X551124Y149798D01*
G37*
G36*
G01X536950D02*
Y145478D01*
X536959Y145450D01*
G02X533119I-1920J-568D01*
G01X533128Y145478D01*
Y149798D01*
X533119Y149826D01*
G02X536959I1920J568D01*
G01X536950Y149798D01*
G37*
G36*
G01X522778D02*
Y145478D01*
X522786Y145450D01*
G02X518946I-1920J-568D01*
G01X518954Y145478D01*
Y149798D01*
X518946Y149826D01*
G02X522786I1920J568D01*
G01X522778Y149798D01*
G37*
G36*
G01X508604D02*
Y145478D01*
X508613Y145450D01*
G02X504773I-1920J-568D01*
G01X504782Y145478D01*
Y149798D01*
X504773Y149826D01*
G02X508613I1920J568D01*
G01X508604Y149798D01*
G37*
G36*
G01X466084D02*
Y145478D01*
X466093Y145450D01*
G02X462253I-1920J-568D01*
G01X462262Y145478D01*
Y149798D01*
X462253Y149826D01*
G02X466093I1920J568D01*
G01X466084Y149798D01*
G37*
G36*
G01X451912D02*
Y145478D01*
X451920Y145450D01*
G02X448080I-1920J-568D01*
G01X448088Y145478D01*
Y149798D01*
X448080Y149826D01*
G02X451920I1920J568D01*
G01X451912Y149798D01*
G37*
G36*
G01X437738D02*
Y145478D01*
X437747Y145450D01*
G02X433907I-1920J-568D01*
G01X433916Y145478D01*
Y149798D01*
X433907Y149826D01*
G02X437747I1920J568D01*
G01X437738Y149798D01*
G37*
G36*
G01X423564D02*
Y145478D01*
X423573Y145450D01*
G02X419733I-1920J-568D01*
G01X419742Y145478D01*
Y149798D01*
X419733Y149826D01*
G02X423573I1920J568D01*
G01X423564Y149798D01*
G37*
G36*
G01X558210Y145074D02*
Y140754D01*
X558219Y140726D01*
G02X554379I-1920J-568D01*
G01X554388Y140754D01*
Y145074D01*
X554379Y145102D01*
G02X558219I1920J568D01*
G01X558210Y145074D01*
G37*
G36*
G01X544038D02*
Y140754D01*
X544046Y140726D01*
G02X540206I-1920J-568D01*
G01X540214Y140754D01*
Y145074D01*
X540206Y145102D01*
G02X544046I1920J568D01*
G01X544038Y145074D01*
G37*
G36*
G01X529864D02*
Y140754D01*
X529873Y140726D01*
G02X526033I-1920J-568D01*
G01X526042Y140754D01*
Y145074D01*
X526033Y145102D01*
G02X529873I1920J568D01*
G01X529864Y145074D01*
G37*
G36*
G01X515690D02*
Y140754D01*
X515699Y140726D01*
G02X511859I-1920J-568D01*
G01X511868Y140754D01*
Y145074D01*
X511859Y145102D01*
G02X515699I1920J568D01*
G01X515690Y145074D01*
G37*
G36*
G01X473172D02*
Y140754D01*
X473180Y140726D01*
G02X469340I-1920J-568D01*
G01X469348Y140754D01*
Y145074D01*
X469340Y145102D01*
G02X473180I1920J568D01*
G01X473172Y145074D01*
G37*
G36*
G01X458998D02*
Y140754D01*
X459006Y140726D01*
G02X455166I-1920J-568D01*
G01X455174Y140754D01*
Y145074D01*
X455166Y145102D01*
G02X459006I1920J568D01*
G01X458998Y145074D01*
G37*
G36*
G01X444824D02*
Y140754D01*
X444833Y140726D01*
G02X440993I-1920J-568D01*
G01X441002Y140754D01*
Y145074D01*
X440993Y145102D01*
G02X444833I1920J568D01*
G01X444824Y145074D01*
G37*
G36*
G01X430652D02*
Y140754D01*
X430660Y140726D01*
G02X426820I-1920J-568D01*
G01X426828Y140754D01*
Y145074D01*
X426820Y145102D01*
G02X430660I1920J568D01*
G01X430652Y145074D01*
G37*
G36*
G01X551124Y135625D02*
Y131305D01*
X551132Y131277D01*
G02X547292I-1920J-568D01*
G01X547300Y131305D01*
Y135625D01*
X547292Y135653D01*
G02X551132I1920J568D01*
G01X551124Y135625D01*
G37*
G36*
G01X536950D02*
Y131305D01*
X536959Y131277D01*
G02X533119I-1920J-568D01*
G01X533128Y131305D01*
Y135625D01*
X533119Y135653D01*
G02X536959I1920J568D01*
G01X536950Y135625D01*
G37*
G36*
G01X522778D02*
Y131305D01*
X522786Y131277D01*
G02X518946I-1920J-568D01*
G01X518954Y131305D01*
Y135625D01*
X518946Y135653D01*
G02X522786I1920J568D01*
G01X522778Y135625D01*
G37*
G36*
G01X508604D02*
Y131305D01*
X508613Y131277D01*
G02X504773I-1920J-568D01*
G01X504782Y131305D01*
Y135625D01*
X504773Y135653D01*
G02X508613I1920J568D01*
G01X508604Y135625D01*
G37*
G36*
G01X466084D02*
Y131305D01*
X466093Y131277D01*
G02X462253I-1920J-568D01*
G01X462262Y131305D01*
Y135625D01*
X462253Y135653D01*
G02X466093I1920J568D01*
G01X466084Y135625D01*
G37*
G36*
G01X451912D02*
Y131305D01*
X451920Y131277D01*
G02X448080I-1920J-568D01*
G01X448088Y131305D01*
Y135625D01*
X448080Y135653D01*
G02X451920I1920J568D01*
G01X451912Y135625D01*
G37*
G36*
G01X437738D02*
Y131305D01*
X437747Y131277D01*
G02X433907I-1920J-568D01*
G01X433916Y131305D01*
Y135625D01*
X433907Y135653D01*
G02X437747I1920J568D01*
G01X437738Y135625D01*
G37*
G36*
G01X423564D02*
Y131305D01*
X423573Y131277D01*
G02X419733I-1920J-568D01*
G01X419742Y131305D01*
Y135625D01*
X419733Y135653D01*
G02X423573I1920J568D01*
G01X423564Y135625D01*
G37*
G36*
G01X558210Y130900D02*
Y126581D01*
X558219Y126553D01*
G02X554379I-1920J-568D01*
G01X554388Y126581D01*
Y130900D01*
X554379Y130928D01*
G02X558219I1920J568D01*
G01X558210Y130900D01*
G37*
G36*
G01X544038D02*
Y126581D01*
X544046Y126553D01*
G02X540206I-1920J-568D01*
G01X540214Y126581D01*
Y130900D01*
X540206Y130928D01*
G02X544046I1920J568D01*
G01X544038Y130900D01*
G37*
G36*
G01X529864D02*
Y126581D01*
X529873Y126553D01*
G02X526033I-1920J-568D01*
G01X526042Y126581D01*
Y130900D01*
X526033Y130928D01*
G02X529873I1920J568D01*
G01X529864Y130900D01*
G37*
G36*
G01X515690D02*
Y126581D01*
X515699Y126553D01*
G02X511859I-1920J-568D01*
G01X511868Y126581D01*
Y130900D01*
X511859Y130928D01*
G02X515699I1920J568D01*
G01X515690Y130900D01*
G37*
G36*
G01X473172D02*
Y126581D01*
X473180Y126553D01*
G02X469340I-1920J-568D01*
G01X469348Y126581D01*
Y130900D01*
X469340Y130928D01*
G02X473180I1920J568D01*
G01X473172Y130900D01*
G37*
G36*
G01X458998D02*
Y126581D01*
X459006Y126553D01*
G02X455166I-1920J-568D01*
G01X455174Y126581D01*
Y130900D01*
X455166Y130928D01*
G02X459006I1920J568D01*
G01X458998Y130900D01*
G37*
G36*
G01X444824D02*
Y126581D01*
X444833Y126553D01*
G02X440993I-1920J-568D01*
G01X441002Y126581D01*
Y130900D01*
X440993Y130928D01*
G02X444833I1920J568D01*
G01X444824Y130900D01*
G37*
G36*
G01X430652D02*
Y126581D01*
X430660Y126553D01*
G02X426820I-1920J-568D01*
G01X426828Y126581D01*
Y130900D01*
X426820Y130928D01*
G02X430660I1920J568D01*
G01X430652Y130900D01*
G37*
G36*
G01X715607Y114177D02*
X715602Y114206D01*
X713203Y118682D01*
X713183Y118703D01*
G02X716480Y120469I1384J1376D01*
G01X716485Y120440D01*
X718883Y115964D01*
X718904Y115944D01*
G02X715607Y114177I-1384J-1377D01*
G37*
G36*
G01X706748D02*
X706742Y114206D01*
X704345Y118682D01*
X704325Y118703D01*
G02X707622Y120469I1384J1376D01*
G01X707628Y120440D01*
X710024Y115964D01*
X710045Y115943D01*
G02X706748Y114177I-1384J-1376D01*
G37*
G36*
G01X636867D02*
X636862Y114206D01*
X634463Y118682D01*
X634443Y118703D01*
G02X637740Y120469I1384J1376D01*
G01X637745Y120440D01*
X640143Y115964D01*
X640164Y115944D01*
G02X636867Y114177I-1384J-1377D01*
G37*
G36*
G01X628882Y120469D02*
X628888Y120440D01*
X631284Y115964D01*
X631305Y115943D01*
G02X628008Y114177I-1384J-1376D01*
G01X628002Y114206D01*
X625605Y118682D01*
X625585Y118703D01*
G02X628882Y120469I1384J1376D01*
G37*
G36*
G01X636867Y99216D02*
X636862Y99245D01*
X634463Y103721D01*
X634443Y103742D01*
G02X637740Y105508I1384J1376D01*
G01X637745Y105479D01*
X640143Y101003D01*
X640164Y100983D01*
G02X636867Y99216I-1384J-1377D01*
G37*
G36*
G01X628882Y105508D02*
X628888Y105479D01*
X631284Y101003D01*
X631305Y100982D01*
G02X628008Y99216I-1384J-1376D01*
G01X628002Y99245D01*
X625605Y103721D01*
X625585Y103742D01*
G02X628882Y105508I1384J1376D01*
G37*
G36*
G01X715614Y84226D02*
X715608Y84253D01*
X713181Y88783D01*
X713161Y88803D01*
G02X716473Y90577I1406J1354D01*
G01X716479Y90550D01*
X718907Y86019D01*
X718927Y85999D01*
G02X715614Y84226I-1407J-1353D01*
G37*
G36*
G01X706748Y84256D02*
X706742Y84285D01*
X704346Y88760D01*
X704325Y88780D01*
G02X707622Y90547I1384J1377D01*
G01X707628Y90518D01*
X710025Y86043D01*
X710045Y86022D01*
G02X706748Y84256I-1384J-1376D01*
G37*
G36*
G01X636874Y84226D02*
X636868Y84253D01*
X634441Y88783D01*
X634421Y88803D01*
G02X637733Y90577I1406J1354D01*
G01X637739Y90550D01*
X640167Y86019D01*
X640187Y85999D01*
G02X636874Y84226I-1407J-1353D01*
G37*
G36*
G01X628882Y90547D02*
X628888Y90518D01*
X631285Y86043D01*
X631305Y86022D01*
G02X628008Y84256I-1384J-1376D01*
G01X628002Y84285D01*
X625606Y88760D01*
X625585Y88780D01*
G02X628882Y90547I1384J1377D01*
G37*
G36*
G01X715607Y69295D02*
X715602Y69324D01*
X713203Y73800D01*
X713183Y73821D01*
G02X716480Y75587I1384J1376D01*
G01X716485Y75558D01*
X718883Y71082D01*
X718904Y71062D01*
G02X715607Y69295I-1384J-1377D01*
G37*
G36*
G01X706748D02*
X706742Y69324D01*
X704345Y73800D01*
X704325Y73821D01*
G02X707622Y75587I1384J1376D01*
G01X707628Y75558D01*
X710024Y71082D01*
X710045Y71061D01*
G02X706748Y69295I-1384J-1376D01*
G37*
G36*
G01X636867D02*
X636862Y69324D01*
X634463Y73800D01*
X634443Y73821D01*
G02X637740Y75587I1384J1376D01*
G01X637745Y75558D01*
X640143Y71082D01*
X640164Y71062D01*
G02X636867Y69295I-1384J-1377D01*
G37*
G36*
G01X628882Y75587D02*
X628888Y75558D01*
X631284Y71082D01*
X631305Y71061D01*
G02X628008Y69295I-1384J-1376D01*
G01X628002Y69324D01*
X625605Y73800D01*
X625585Y73821D01*
G02X628882Y75587I1384J1376D01*
G37*
G36*
G01X499367Y16458D02*
X498086Y15177D01*
X471247D01*
X469355Y17069D01*
X440230D01*
X431290Y26009D01*
Y60131D01*
X436409Y65250D01*
X474239D01*
X474500Y65511D01*
Y70211D01*
X477489Y73200D01*
X480879D01*
G02X482721I921J-2000D01*
G01X499411D01*
X507500Y65111D01*
Y47109D01*
X499367Y38976D01*
Y16458D01*
G37*
G36*
G01X769908Y294122D02*
X769913Y290947D01*
G02X767276Y290250I-1410J-2D01*
G03X766580I-348J-197D01*
G02X763943Y290931I-1227J695D01*
G01X763915Y294089D01*
G02X766556Y294789I1410J13D01*
G03X767257Y294794I349J195D01*
G02X769908Y294126I1241J-670D01*
G01Y294122D01*
G37*
G36*
G01X779362Y290928D02*
G02X776725Y290250I-1410J17D01*
G03X776029I-348J-197D01*
G02X773392Y290959I-1227J695D01*
G01X773425Y294103D01*
G02X776062Y294782I1410J-15D01*
G03X776759Y294783I348J197D01*
G02X779399Y294076I1230J-690D01*
G01X779362Y290928D01*
G37*
G36*
G01X760464Y290943D02*
G02X757827Y290249I-1410J1D01*
G03X757132I-348J-198D01*
G02X754495Y290944I-1227J695D01*
G01Y294093D01*
G02X757132Y294788I1410J0D01*
G03X757828I348J197D01*
G02X760465Y294093I1227J-694D01*
G01X760464Y292354D01*
Y290943D01*
G37*
G36*
G01X788818Y294071D02*
X788814Y292330D01*
G03X789493Y292042I400J-1D01*
G02X790545Y292469I1052J-1082D01*
G01X793694D01*
G02X794830Y289964I0J-1510D01*
G03X795130Y289301I301J-263D01*
G01X796845Y289294D01*
G02X796833Y286274I-6J-1510D01*
G01X795125Y286281D01*
G03X794820Y285620I-2J-400D01*
G02X795185Y284639I-1145J-984D01*
G01Y284634D01*
X795189Y281510D01*
G02X794829Y280529I-1510J-2D01*
G03X795134Y279870I305J-259D01*
G01X796865Y279874D01*
G02X796871Y276854I3J-1510D01*
G01X795176Y276850D01*
G03X794876Y276188I2J-400D01*
G02X795247Y275169I-1139J-992D01*
G01X795192Y272037D01*
G02X794817Y271067I-1510J26D01*
G03X795121Y270403I300J-264D01*
G01X796835Y270420D01*
G02X796865Y267400I15J-1510D01*
G01X795135Y267383D01*
G03X794832Y266726I4J-400D01*
G02X795184Y265770I-1158J-969D01*
G01X795209Y262646D01*
G02X792189Y262622I-1510J-12D01*
G01X792164Y265745D01*
G02X792807Y266994I1510J13D01*
G03X792809Y267648I-229J328D01*
G02X792849Y270138I874J1231D01*
G03Y270804I-221J333D01*
G02X792172Y272091I833J1260D01*
G01X792227Y275222D01*
G02X792865Y276429I1510J-26D01*
G03X792853Y277091I-230J327D01*
G02X792823Y279604I822J1266D01*
G03X792824Y280263I-226J330D01*
G02X792169Y281506I855J1245D01*
G01X792165Y284634D01*
G02X792838Y285893I1510J2D01*
G03X792844Y286555I-221J333D01*
G02X792563Y288787I859J1242D01*
G03X792261Y289449I-302J262D01*
G01X790544D01*
G02X789259Y290168I1J1510D01*
G03X788583Y290176I-341J-210D01*
G02X786174Y290250I-1182J769D01*
G03X785478I-348J-197D01*
G02X782841Y290947I-1227J695D01*
G01X782848Y294067D01*
G02X785483Y294763I1410J-3D01*
G03X786179Y294765I347J198D01*
G02X788818Y294071I1229J-691D01*
G37*
G54D52*
X305906Y182874D03*
G54D51*
X201801Y684252D03*
X225601D03*
G54D53*
X305906Y388386D03*
G54D46*
X18700Y54650D03*
X901000Y21400D03*
X902500Y676000D03*
G54D54*
X488838Y137225D03*
G54D55*
Y164744D03*
G54D49*
X90157Y413583D03*
X309055Y157677D03*
G54D44*
X309252Y413583D03*
G54D58*
X297146Y266732D03*
Y329724D03*
Y317126D03*
X314666Y298228D03*
X297146Y304528D03*
X314666Y285630D03*
Y361220D03*
Y348622D03*
X297146Y367520D03*
Y354922D03*
X314666Y336024D03*
G54D56*
X652756Y180000D03*
G54D45*
X89764Y238386D03*
G54D59*
X314666Y323425D03*
Y310827D03*
X297146Y291929D03*
Y279331D03*
X314666Y373819D03*
X297146Y342323D03*
G54D57*
X865353Y332598D03*
G54D50*
X163189Y669291D03*
G54D47*
X70866Y98425D03*
Y472441D03*
X314961D03*
X405512Y39370D03*
X364173Y740157D03*
X612205Y433071D03*
Y740157D03*
X875984Y433071D03*
X875985Y740157D03*
G54D48*
X49213D03*
X875985Y59055D03*
%LPC*%
G75*
G36*
G01X497464Y16677D02*
X471869D01*
X469977Y18569D01*
X440852D01*
X432790Y26631D01*
Y59509D01*
X437031Y63750D01*
X474861D01*
X476000Y64889D01*
Y69589D01*
X478111Y71700D01*
X498789D01*
X506000Y64489D01*
Y47731D01*
X497867Y39598D01*
Y17080D01*
X497464Y16677D01*
G37*
%LPD*%
G75*
G54D12*
X56102Y24606D03*
X103346Y34449D03*
X590300Y574400D03*
G54D26*
X339331Y49803D03*
X360669Y91929D03*
G54D14*
X38590Y55260D03*
X30270Y48330D03*
X31100Y458733D03*
X26576Y457406D03*
X41250Y494600D03*
X53524Y521269D03*
Y526995D03*
X75405Y521695D03*
X69778D03*
X64151D03*
X49600Y496050D03*
X55300Y495600D03*
X62276Y550493D03*
X74151Y545516D03*
X74498Y551757D03*
X71002Y539219D03*
X74076Y535966D03*
X75508Y542198D03*
X71002Y542368D03*
X67852Y539219D03*
X71002Y545518D03*
Y558117D03*
X74152Y567565D03*
X71002D03*
Y564396D03*
X74152Y580163D03*
Y577013D03*
X71002Y561266D03*
X67853Y564416D03*
X75066Y563235D03*
X71002Y554967D03*
X67853D03*
X78276Y545566D03*
X67853Y542368D03*
X71002Y548668D03*
X52408Y543876D03*
X64701Y542366D03*
X52603Y549526D03*
X52485Y555153D03*
X53300Y560879D03*
X67853Y570715D03*
X74152Y583312D03*
X64703Y586463D03*
X63456Y555041D03*
X64701Y567566D03*
Y561266D03*
X67853D03*
Y577015D03*
X53524Y532622D03*
X52613Y538242D03*
X53302Y567317D03*
X59200Y582200D03*
X38550Y617950D03*
X47150Y665500D03*
X76100Y697100D03*
X97600Y54810D03*
X89070Y62600D03*
X114390Y453185D03*
X102250Y455000D03*
X108300Y435900D03*
X118108Y453159D03*
X121826Y453156D03*
X128968Y452741D03*
X125353Y452385D03*
X132109Y451199D03*
X136021Y451394D03*
X127812Y445066D03*
X117200Y495200D03*
X105920Y477098D03*
X141980Y508590D03*
X97637Y492891D03*
X118900Y522000D03*
X138000Y485900D03*
X102700Y507100D03*
X116500Y477000D03*
X144500Y489500D03*
X92286Y521695D03*
X81032D03*
X86659D03*
X97913D03*
X114500Y490000D03*
X101800Y493000D03*
X137050Y476346D03*
X132774Y497000D03*
X86750Y542368D03*
X126337Y554085D03*
X130311Y546700D03*
X81276Y548766D03*
X119605Y548705D03*
X86750Y539218D03*
X83600Y545518D03*
X89899D03*
X127300Y543200D03*
X89899Y539218D03*
X117200Y546300D03*
X83600Y539219D03*
X86750Y545518D03*
X122600Y557480D03*
X86750Y554965D03*
X130607Y569636D03*
X86750Y558115D03*
X126347Y569556D03*
X83600Y551817D03*
X117400Y567650D03*
X83600Y573865D03*
X86750Y586463D03*
Y583313D03*
X83601Y580164D03*
X89899Y577014D03*
X86750D03*
X83600Y564415D03*
X86750D03*
X83600Y561265D03*
X96570Y581730D03*
X86750Y551815D03*
X123300Y530300D03*
X133800Y528500D03*
X123200Y534600D03*
X143500Y529000D03*
X93744Y542019D03*
X133554Y537374D03*
X93051Y587466D03*
X83600Y567565D03*
X93049Y573864D03*
X89899Y567565D03*
X93048Y580164D03*
X89899Y561265D03*
X86750D03*
X94720Y557158D03*
X92600Y535623D03*
X96371Y534124D03*
X123370Y606700D03*
X119600D03*
X118500Y638100D03*
X140700Y657700D03*
X130800Y656100D03*
X127401Y606930D03*
X123500Y613100D03*
X93053Y606734D03*
X142447Y611714D03*
X119000Y633200D03*
X120500Y651800D03*
X134650Y612900D03*
X144750Y606350D03*
X141971Y624700D03*
X98200Y616900D03*
X129800Y630700D03*
X105600Y597000D03*
X105400Y601300D03*
X104600Y609900D03*
X105600Y605900D03*
X104600Y614000D03*
X104500Y618800D03*
X117050Y602000D03*
X116200Y611600D03*
X116023Y607423D03*
X119400Y614100D03*
X116500Y621000D03*
X116400Y616900D03*
X130800Y606700D03*
X138500Y637900D03*
X130500Y638600D03*
X134700D03*
X129903Y634500D03*
X107100Y679600D03*
X106879Y707245D03*
X125376Y701124D03*
X106355Y710745D03*
X106635Y701465D03*
X87683Y698924D03*
X84600Y688000D03*
X119849Y709715D03*
X186602Y459767D03*
X197085Y459899D03*
X190278Y459865D03*
X193686Y459799D03*
X176000Y460200D03*
X172200Y460100D03*
X157496Y461248D03*
X166600Y509800D03*
X166700Y499800D03*
X208370Y491570D03*
X183100Y499800D03*
X170838Y481762D03*
X146300Y502600D03*
X146112Y509412D03*
X158100Y493000D03*
X158400Y513600D03*
X155001Y513707D03*
X182874Y513591D03*
X178869Y513593D03*
X174900Y499800D03*
X166600Y513600D03*
X170700D03*
X172370Y463798D03*
X187000Y468000D03*
X146293Y464338D03*
X146193Y476938D03*
X146293Y472738D03*
X186600Y477700D03*
X187000Y499500D03*
X146500Y492500D03*
X183300Y493100D03*
X145400Y524046D03*
X176100Y473200D03*
X174700Y513900D03*
X182300Y509600D03*
X184780Y526990D03*
X187167Y513167D03*
X191100Y513367D03*
X154500Y487000D03*
X178869Y509793D03*
X209800Y478500D03*
X205447Y487762D03*
X158290Y502380D03*
X182874Y523590D03*
X205516Y467968D03*
X170700Y509800D03*
X170900Y500000D03*
X165900Y524100D03*
X209256Y467946D03*
X172100Y467300D03*
X176800Y492200D03*
X175805Y524073D03*
X206180Y509524D03*
X191100Y526000D03*
X195149Y513751D03*
X150500Y493000D03*
X190950Y482100D03*
X196200Y482600D03*
X200100Y491700D03*
X146216Y486045D03*
X196243Y486782D03*
X159480Y506590D03*
X155540Y506510D03*
X195300Y498900D03*
X195379Y510158D03*
X150162Y525937D03*
X148527Y519491D03*
X191725Y523074D03*
X148409Y575672D03*
X144876Y590854D03*
X148409Y579353D03*
X144876Y587173D03*
X175100Y529100D03*
X203610Y529397D03*
X168390Y532060D03*
X184830Y529960D03*
X149419Y535654D03*
X191200Y529400D03*
X199400D03*
X208000Y529300D03*
X149242Y531080D03*
X152584Y532922D03*
X152415Y540014D03*
X194490Y645390D03*
X191370Y608190D03*
X208700Y625149D03*
X200879Y614739D03*
X145900Y641300D03*
X164800Y640200D03*
X173000Y640400D03*
X193610Y640040D03*
X189500Y639700D03*
X178140Y630330D03*
X196249Y630091D03*
X199400Y628646D03*
X151550Y629800D03*
X163200Y610070D03*
X160420Y610170D03*
X184050Y629500D03*
X181176Y627600D03*
X209093Y615849D03*
X166690Y615060D03*
X166600Y617850D03*
X195900Y649350D03*
X203400Y649600D03*
X146800Y629900D03*
X180700Y640460D03*
X204800Y617440D03*
X204642Y621140D03*
X177300Y626800D03*
X204150Y645180D03*
X199600Y650100D03*
X192960Y628510D03*
X187900Y628500D03*
X152700Y640800D03*
X161000Y634300D03*
X157200Y634200D03*
X206700Y695400D03*
X162100Y711215D03*
X151949Y691715D03*
X175233Y704382D03*
X163349Y702715D03*
X150849Y710215D03*
X163260Y706988D03*
X169070Y696220D03*
X159519Y694455D03*
X193500Y663000D03*
X200400Y694700D03*
X196900Y661350D03*
X206300Y661100D03*
X181300Y679100D03*
X185100Y705600D03*
X184800Y709300D03*
X190200Y671000D03*
X187500Y673100D03*
X272000Y461800D03*
X268350Y461950D03*
X275100Y460300D03*
X259000Y453900D03*
X251700Y443600D03*
X268900Y445150D03*
X244700Y451200D03*
X236100Y445100D03*
X239300Y443800D03*
X243000D03*
X247900Y445300D03*
X260600Y442600D03*
X250500Y451300D03*
X224500Y445600D03*
X254900Y453900D03*
X232200Y445600D03*
X275700Y490300D03*
X244900Y527300D03*
X228150Y525750D03*
X275400Y470300D03*
X213100Y476300D03*
X261200Y525400D03*
X242500Y523500D03*
X254500Y509600D03*
X213100Y472900D03*
X275200Y474500D03*
X258100Y516400D03*
X227500Y512200D03*
X265148Y524595D03*
X228700Y490717D03*
X230700Y486658D03*
X249050Y527150D03*
X249640Y495080D03*
X234700Y490900D03*
X258381Y509498D03*
X225914Y523051D03*
X231800Y512100D03*
X223600Y512400D03*
X213359Y480489D03*
X238400Y511300D03*
X265274Y509512D03*
X267800Y479900D03*
X245743Y546963D03*
X270021Y549394D03*
X257000Y548400D03*
X263216Y554697D03*
X254530Y564300D03*
X251446Y553754D03*
X254500Y579500D03*
X273500Y567400D03*
X254300Y586500D03*
X273400Y590902D03*
X231434Y562844D03*
X234300Y582300D03*
X231200Y576800D03*
X231000Y571900D03*
X257300Y537500D03*
X214900Y529400D03*
X234943Y565199D03*
X254600Y567700D03*
X260731Y561264D03*
X260741Y542700D03*
X264333Y528926D03*
X254905Y555761D03*
X258528Y555161D03*
X259100Y567706D03*
X257000Y571700D03*
X223900Y531200D03*
X228100Y545500D03*
X228800Y542100D03*
X228313Y552169D03*
X262000Y586900D03*
X257851Y580080D03*
X270145Y557526D03*
X261308Y583388D03*
X237100Y590000D03*
X257700Y586400D03*
X261500Y576400D03*
X261600Y580000D03*
X257891Y563786D03*
X257600Y576500D03*
X233607Y557671D03*
X254500Y575070D03*
X261100Y571600D03*
X234800Y572000D03*
X232400Y533200D03*
X248900Y545700D03*
X267957Y537304D03*
X274623Y578896D03*
X271357Y537253D03*
X233036Y550942D03*
X213800Y631200D03*
X212308Y605949D03*
X229796Y610104D03*
X270000Y602400D03*
X222950Y647900D03*
X255570Y616631D03*
X258962Y616384D03*
X236000Y647400D03*
X225900Y630700D03*
X231500Y659100D03*
X228149Y600094D03*
X242710Y604620D03*
X226471Y649129D03*
X243322Y597509D03*
X251314Y598106D03*
X251338Y601506D03*
X258550Y606527D03*
Y610096D03*
X215606Y645806D03*
X229500Y631500D03*
X212900Y619201D03*
X273714Y629870D03*
X266571Y630071D03*
X245100Y647200D03*
X272200Y648550D03*
X221238Y620524D03*
X234205Y598743D03*
X233258Y595693D03*
X232130Y612950D03*
X251900Y609600D03*
X259777Y638873D03*
X242000Y656400D03*
X255733Y622329D03*
X253196Y706062D03*
X255050Y675750D03*
X254800Y689400D03*
X269200Y699600D03*
X258423Y711343D03*
X268520Y719420D03*
X270900Y667200D03*
X237509Y674915D03*
X266200Y679400D03*
X268384Y662909D03*
X263700Y723500D03*
X264700Y700000D03*
X214270Y695095D03*
X275300Y668749D03*
X217638Y695562D03*
X235000Y692900D03*
X262323Y716917D03*
X255200Y680950D03*
X239400Y677900D03*
X266300Y692574D03*
X254648Y745463D03*
X311715Y20397D03*
X310353Y62159D03*
X326553Y34687D03*
X339232Y113960D03*
X338743Y122894D03*
X305700Y197600D03*
X295841Y176793D03*
X323582Y179064D03*
X299107Y177740D03*
X295462Y173414D03*
X304231Y265048D03*
X335000Y226992D03*
X305782Y230874D03*
X335082Y231574D03*
X322301Y220009D03*
X305782Y217274D03*
X305682Y224074D03*
X305782Y220674D03*
X305454Y244461D03*
X334998Y255520D03*
X305373Y251101D03*
X334998Y259033D03*
X306412Y254339D03*
X335060Y262516D03*
X305882Y234274D03*
X305772Y237673D03*
X321700Y246000D03*
X321600Y250000D03*
X305781Y241076D03*
X334582Y287284D03*
Y283784D03*
X307567Y331592D03*
Y328092D03*
X304267Y318892D03*
Y315392D03*
X307567Y306292D03*
Y302792D03*
X304267Y293692D03*
Y290192D03*
X328182Y325174D03*
Y321674D03*
X334582Y312574D03*
Y309074D03*
X328182Y299977D03*
Y296477D03*
X307567Y281092D03*
Y277592D03*
X304231Y268548D03*
X328913Y274414D03*
X334017Y272000D03*
X337808Y288709D03*
X304267Y369292D03*
Y365792D03*
X307567Y356692D03*
Y353192D03*
X304267Y344092D03*
Y340592D03*
X328182Y375518D03*
Y372018D03*
X334582Y362974D03*
Y359474D03*
Y337771D03*
Y334271D03*
X328182Y350371D03*
Y346871D03*
X334000Y382700D03*
X303680Y380972D03*
X316900Y384100D03*
X319679Y387121D03*
X314000Y390500D03*
X335800Y379800D03*
X338800Y435100D03*
X281200Y453500D03*
X333850Y458400D03*
X286700Y457500D03*
X323759Y435145D03*
X327159Y435201D03*
X276634Y498311D03*
X325136Y519316D03*
X333922Y527323D03*
X340961Y511600D03*
X298335Y521458D03*
X304800Y512800D03*
X286797Y516522D03*
X308687Y519193D03*
X302307Y505799D03*
X298907Y505851D03*
X292100Y516000D03*
X297400Y517981D03*
X336600Y504500D03*
X336800Y499967D03*
X325400Y505800D03*
X282403Y474500D03*
X282400Y470200D03*
X328200Y511600D03*
X331200Y508900D03*
X299448Y511300D03*
X277603Y479948D03*
X332821Y515415D03*
X278400Y463300D03*
X280939Y504705D03*
X314400Y505750D03*
X334650Y508900D03*
X300476Y546907D03*
X325774Y547428D03*
X331700Y587896D03*
X303520Y550085D03*
X296835Y591015D03*
X280646Y557150D03*
X303500Y582200D03*
X333847Y531105D03*
X286195Y530579D03*
X291800Y576708D03*
X333800Y534830D03*
X329840Y572710D03*
X337550Y534619D03*
X295824Y578108D03*
X325475Y572818D03*
X323659Y557310D03*
X334900Y586100D03*
X333512Y553888D03*
X281610Y590260D03*
X324200Y565300D03*
X281490Y586862D03*
X337300Y583000D03*
X336367Y549943D03*
X294107Y560762D03*
X330729Y557268D03*
X298000Y561000D03*
X327059Y557247D03*
X288309Y566467D03*
X328580Y568120D03*
X291000Y570810D03*
X320954Y572631D03*
X277048Y590470D03*
X319529Y562413D03*
X319252Y566509D03*
X285912Y538750D03*
X318736Y549697D03*
X280100Y532100D03*
X322889Y529380D03*
X322843Y533254D03*
X279664Y535473D03*
X328771Y549035D03*
X332808Y547575D03*
X332834Y543993D03*
X337346Y545100D03*
X341316Y545000D03*
X282000Y583500D03*
X298514Y550184D03*
X293087Y530571D03*
X325687Y551368D03*
X319430Y557486D03*
X276839Y582309D03*
X277441Y539882D03*
X308200Y593153D03*
X310292Y532128D03*
X278443Y648857D03*
X284495Y613130D03*
X286700Y622190D03*
X340100Y631417D03*
X339751Y616882D03*
Y613185D03*
X335036Y603039D03*
X338733D03*
X325300Y648700D03*
X294500Y630600D03*
X298100Y630650D03*
X330400Y644300D03*
X334700Y644500D03*
X302459Y599531D03*
X306100Y599500D03*
X306231Y602898D03*
X302180Y603084D03*
X335100Y650600D03*
X338100Y635800D03*
X331718Y655832D03*
X329100Y650700D03*
X317689Y599833D03*
X287200Y632600D03*
X290900Y630900D03*
X278769Y700697D03*
X321800Y678500D03*
X281000Y678000D03*
X304400Y665100D03*
X316465Y716063D03*
X340500Y711750D03*
X335750Y664700D03*
X288700Y667900D03*
X340100Y718200D03*
X327250Y701500D03*
X327162Y696776D03*
X282300Y700100D03*
X316000Y671850D03*
X276800Y697925D03*
X338669Y691580D03*
X339804Y679030D03*
X340403Y699400D03*
X340300Y703100D03*
X336200Y677000D03*
X289700Y678830D03*
X280646Y717540D03*
X276100Y677700D03*
X300100Y670300D03*
X304700Y668500D03*
X291700Y737000D03*
X287620Y737300D03*
X290000Y727000D03*
X313873Y735907D03*
X314100Y739300D03*
X370870Y45605D03*
X368059Y57759D03*
X354798Y22452D03*
X386759Y79693D03*
X390456D03*
X342539Y120370D03*
X369253Y88733D03*
X367287Y77118D03*
X381269Y94981D03*
X384666Y93741D03*
X349206Y129948D03*
X390964Y87226D03*
X388700Y89800D03*
X370149Y167337D03*
X370882Y163688D03*
X387202Y164664D03*
X387393Y160859D03*
X404727Y162141D03*
X392102Y175384D03*
X400205Y158209D03*
Y161906D03*
X392458Y171676D03*
X400430Y147190D03*
X361792Y243154D03*
X372888Y208022D03*
X359882Y203458D03*
X347482Y254774D03*
X341882Y251064D03*
X342885Y276301D03*
X342958Y279701D03*
X383170Y329807D03*
X345582Y380874D03*
X344732Y393882D03*
Y390274D03*
X383285Y347114D03*
X383327Y343379D03*
X396561Y351418D03*
X346600Y375000D03*
X344732Y386874D03*
X365100Y348300D03*
X372491Y378025D03*
X365200Y344400D03*
X378492Y378175D03*
X383030Y352442D03*
X367358Y372531D03*
X367471Y369120D03*
X360100Y453500D03*
X342700Y435200D03*
X350491Y453809D03*
X372000Y452100D03*
X369900Y458700D03*
X387450Y454558D03*
X387396Y458126D03*
X384395Y449114D03*
X374700Y460300D03*
X350400Y459000D03*
X381106Y441241D03*
X350400Y462400D03*
X374650Y456771D03*
X346500Y435200D03*
X364500Y453700D03*
X367400Y461200D03*
X355400Y453800D03*
X357900Y450800D03*
X357450Y491450D03*
X364500Y525260D03*
X369300Y508700D03*
X344400Y505400D03*
X344500Y500300D03*
X363500Y464700D03*
X372000Y477710D03*
X355300Y502700D03*
X357700Y499000D03*
X400080Y500854D03*
X384849Y525499D03*
Y521681D03*
X355300Y506100D03*
Y513500D03*
X386367Y474700D03*
X400080Y519500D03*
Y491107D03*
Y523903D03*
Y528243D03*
X389349Y480100D03*
X381986Y515631D03*
X374751Y485636D03*
X374715Y498722D03*
X366950Y464700D03*
X390229Y508189D03*
X341500Y520400D03*
X373699Y521160D03*
X359100Y503200D03*
X374800Y516912D03*
X387450Y467000D03*
X389288Y483500D03*
X358800Y478000D03*
X373800Y503000D03*
X370900Y464700D03*
X378267Y496100D03*
X349088Y500296D03*
X384950Y560496D03*
X383000Y577000D03*
X386305Y581647D03*
X362700Y551200D03*
X361279Y581647D03*
X362100Y574700D03*
X349000Y581360D03*
X379050Y539931D03*
X341740Y535800D03*
X352279Y580294D03*
X346303Y591947D03*
X386723Y544565D03*
X342440Y571770D03*
X361900Y570800D03*
X369500Y542900D03*
X388641Y549747D03*
X400093Y536351D03*
X399726Y562327D03*
X399946Y558677D03*
X344163Y553395D03*
X345259Y557566D03*
X391993Y582154D03*
X362300Y555200D03*
X343840Y566440D03*
X348300Y565400D03*
X364900Y585171D03*
X364964Y588771D03*
X372939Y559838D03*
X346590Y572090D03*
X350278Y572306D03*
X366270Y563400D03*
X373222Y535938D03*
X370247Y546218D03*
X370223Y549965D03*
X384950Y551876D03*
Y555276D03*
X383056Y563675D03*
X400060Y554743D03*
X393912Y571899D03*
X393910Y575305D03*
X341493Y541250D03*
X393912Y578705D03*
X348000Y612661D03*
X352720Y600970D03*
X367133Y596067D03*
X382380Y612277D03*
X352400Y626102D03*
X372408Y629626D03*
X364014Y593996D03*
X343797Y631417D03*
X381967Y616123D03*
X361227Y630300D03*
X377700Y595000D03*
X383199Y623168D03*
X382438Y608755D03*
X384158Y638105D03*
X380443D03*
X400064Y652598D03*
X384300Y619925D03*
X384220Y700618D03*
X367600Y696800D03*
X396166Y692630D03*
X343200Y667600D03*
X389999Y664697D03*
X367700Y685450D03*
X343338Y679236D03*
X399999Y673422D03*
X396419Y679708D03*
X398983Y706749D03*
X382308Y665022D03*
X396419Y686586D03*
X372350Y698400D03*
X399093Y703350D03*
X380300Y703000D03*
X399154Y699950D03*
X341900Y690350D03*
X346600Y714500D03*
X346000Y684300D03*
X383800Y688400D03*
X380387Y685261D03*
X392500Y673500D03*
X392800Y677600D03*
X341934Y662794D03*
X378595Y664960D03*
X388626Y715509D03*
X392500Y692500D03*
X355298Y711750D03*
X396419Y683186D03*
X459950Y58000D03*
X469058Y49156D03*
X458972Y49634D03*
X462625Y49881D03*
X467300Y20000D03*
X450454Y38147D03*
X448520Y49979D03*
X430800Y22200D03*
X433600Y19900D03*
X428001Y25269D03*
X433400Y63373D03*
X438600Y91033D03*
X419662Y71426D03*
X423340Y71621D03*
X469901Y94047D03*
X415211Y71263D03*
X461736Y111300D03*
X442800Y90934D03*
X496700Y32100D03*
X482693Y42200D03*
X478500Y19775D03*
X490050Y45900D03*
X477400Y69300D03*
X512806Y49494D03*
X473151Y50052D03*
X521200Y57600D03*
X503814Y56676D03*
X515500Y57900D03*
X486568Y38006D03*
X486114Y41700D03*
X496430Y22890D03*
X491270Y18877D03*
X485674Y32924D03*
X524950Y16120D03*
X473172Y95508D03*
X479147Y102165D03*
X490100Y111300D03*
X486400Y74700D03*
X481800Y71200D03*
X513909Y85849D03*
X510408Y85779D03*
X599422Y51662D03*
X568430Y50010D03*
X596489Y14110D03*
X559600Y47600D03*
X575550Y42800D03*
X601311Y13521D03*
X569300Y66274D03*
X545200Y69000D03*
X596300Y66950D03*
X549550Y61900D03*
X597950Y58950D03*
X564500Y64100D03*
X573600Y49750D03*
X584550Y80750D03*
X559900Y88400D03*
X563268Y88872D03*
X540179Y111036D03*
X539346Y114333D03*
X578900Y82500D03*
X551500Y82400D03*
X599682Y103715D03*
X547100Y79900D03*
X578400Y74500D03*
X562160Y178600D03*
X598964Y354128D03*
X596077Y369579D03*
X602075Y339970D03*
X586155Y393023D03*
X593064Y400910D03*
X593229Y397308D03*
X666535Y26149D03*
X665800Y7550D03*
X666400Y22200D03*
X619980Y197550D03*
X634000Y187500D03*
X630800Y147600D03*
X634800Y147700D03*
X644100Y203350D03*
X634450Y252100D03*
X631550Y249850D03*
X625926Y247530D03*
X627200Y253550D03*
X625250Y264250D03*
X625550Y244150D03*
Y240750D03*
X645516Y225334D03*
X620750Y258050D03*
X642547Y226992D03*
X632958Y231000D03*
X633109Y234397D03*
X632900Y238000D03*
X628300Y230550D03*
X625700Y235750D03*
X640141Y259859D03*
X640400Y217600D03*
X636491Y217592D03*
X633092Y217496D03*
X659500Y205300D03*
X665500Y201900D03*
X662900Y205300D03*
X645400Y264050D03*
X620160Y203500D03*
X660700Y292200D03*
X634830Y292095D03*
X638453Y291949D03*
X633400Y274600D03*
X657500Y281500D03*
X652850Y269600D03*
X642300Y276450D03*
X649000Y273500D03*
X652100Y279300D03*
X648000Y281300D03*
X656700Y305607D03*
X664600Y306100D03*
X648700Y303600D03*
X652500Y305707D03*
X638603Y296320D03*
X642003Y296249D03*
X645403Y296229D03*
X631069Y292512D03*
X654600Y367600D03*
X639318Y354003D03*
X643082Y353941D03*
X629239Y387969D03*
X620100Y384100D03*
X608600Y362600D03*
X659300Y373100D03*
X637000Y373856D03*
X632220Y389694D03*
X607800Y382362D03*
X607100Y351200D03*
X638360Y383805D03*
X642270Y383869D03*
X605400Y393400D03*
X618600Y364375D03*
X609240Y370337D03*
X616900Y343000D03*
X615150Y364200D03*
X640968Y370425D03*
X606626Y354723D03*
X637353Y379591D03*
X636963Y405999D03*
X632180Y397968D03*
X654300Y504100D03*
X613000Y463000D03*
X666216Y470684D03*
X632800Y561600D03*
X620160Y544793D03*
X635970Y557600D03*
X638660Y568043D03*
X616160Y542700D03*
X614000Y561250D03*
X606600Y551100D03*
X677770Y196410D03*
X730550Y179050D03*
X732000Y185900D03*
X716650Y174400D03*
X674300Y198900D03*
X718121Y256326D03*
X718089Y246834D03*
X718098Y259423D03*
X718072Y265748D03*
X718089Y249984D03*
X718129Y253144D03*
X693800Y264300D03*
X725466Y200819D03*
X707923Y219765D03*
X708900Y214500D03*
X718111Y224802D03*
X706500Y212150D03*
X709615Y223228D03*
X718111Y231101D03*
X696300Y215750D03*
X702900Y212350D03*
X707679Y233664D03*
X718111Y227952D03*
X722322Y200935D03*
X704279Y226664D03*
X705529Y231064D03*
X705779Y236764D03*
X706079Y240664D03*
X710716Y235827D03*
X714945Y234230D03*
X726988Y204312D03*
X718123Y201101D03*
X710079Y203664D03*
X718895Y207125D03*
X705364Y205864D03*
X713168Y207689D03*
X718111Y221653D03*
X733859Y215355D03*
X718110Y234252D03*
X709679Y239164D03*
X727560Y215355D03*
X716116Y207469D03*
X718111Y237401D03*
X709079Y229564D03*
X703979Y219995D03*
X718111Y240550D03*
X711812Y243700D03*
X714961D03*
X730709Y215355D03*
X724410D03*
X732264Y204312D03*
X703320Y203900D03*
X733859Y212206D03*
X729800Y208400D03*
X730709Y221654D03*
X733858D03*
X724410D03*
Y234252D03*
Y240551D03*
Y246850D03*
Y253150D03*
Y227953D03*
Y265748D03*
Y259449D03*
X704579Y261964D03*
X682030Y253630D03*
X706100Y250000D03*
X690600Y230700D03*
X691243Y211743D03*
X692600Y201300D03*
X677800Y215900D03*
X706796Y295829D03*
X726895Y309117D03*
X711799Y304234D03*
X713339Y306954D03*
X724063Y306305D03*
X698039Y285854D03*
X707834Y293060D03*
X707079Y286964D03*
X704079Y300964D03*
X719200Y307400D03*
X705579Y298464D03*
X695508Y288964D03*
X710679Y267894D03*
X721230Y284653D03*
X718099Y290964D03*
X710329Y285214D03*
X718117Y281465D03*
X718080Y284653D03*
X701708Y292364D03*
X706277Y279162D03*
X718072Y278346D03*
X708409Y276771D03*
X733892Y297246D03*
X730708Y297243D03*
X714619Y303884D03*
X692750Y293200D03*
X718109Y272034D03*
X694307Y283485D03*
X722468Y308964D03*
X727558Y297243D03*
X733859Y272048D03*
X690579Y299964D03*
X675555Y318736D03*
X672350Y317600D03*
X724409Y297243D03*
X700323Y283078D03*
X716300Y331340D03*
X733859Y284646D03*
X695300Y306700D03*
X718099Y287814D03*
X712410Y331320D03*
X702250Y329650D03*
X733857Y290944D03*
X727558D03*
X730300Y314900D03*
X724410Y272047D03*
Y278346D03*
Y284645D03*
X669950Y310950D03*
X681800Y287950D03*
X718137Y275186D03*
X702939Y281484D03*
X718109Y268934D03*
X714949Y287814D03*
X718300Y362900D03*
X722500Y353000D03*
X718000D03*
X713500Y362900D03*
X729900Y393200D03*
X709006Y410206D03*
X721504Y402321D03*
X699900Y453600D03*
X691813Y407210D03*
X691874Y410741D03*
X691873Y403800D03*
X690550Y453850D03*
X690300Y460200D03*
X720900Y412900D03*
X696800Y476400D03*
X689100Y507900D03*
X730600Y493100D03*
X716078Y492334D03*
X672500Y507100D03*
X696000Y508400D03*
X715391Y479109D03*
X725000Y576100D03*
X714800Y567956D03*
X710000Y549100D03*
X710100Y545600D03*
X705176Y593429D03*
X717450Y551554D03*
X697200Y529200D03*
X705676Y562429D03*
X702515Y597064D03*
X693900Y597800D03*
X703800Y608400D03*
X712708Y603038D03*
X723369Y599835D03*
X722122Y611840D03*
X769812Y53660D03*
X756431Y54010D03*
X736803Y52087D03*
X779400Y54750D03*
X746500Y47200D03*
X780815Y47062D03*
X776600Y35250D03*
X762765Y42200D03*
X781250Y101750D03*
X779594Y126865D03*
X762000Y113000D03*
X763825Y89975D03*
X776500Y82700D03*
X750500Y118500D03*
X750600Y114200D03*
X769500Y91000D03*
X792600Y101300D03*
X772800Y107550D03*
X776850Y115050D03*
X738160Y199480D03*
X749900Y185200D03*
X786343Y179959D03*
X745700Y185900D03*
X769100Y187800D03*
X786388Y183429D03*
X772810Y179901D03*
X772700Y183300D03*
X737000Y185900D03*
X765900Y191900D03*
X768579Y203964D03*
X764900Y207200D03*
X761600Y207300D03*
X787402Y240552D03*
Y243701D03*
X793700Y256262D03*
X752759Y218499D03*
X755909Y218514D03*
X790550Y253150D03*
X799972Y256309D03*
X781080Y265763D03*
X784258Y262618D03*
X777967Y262576D03*
X790523Y256289D03*
X800021Y243717D03*
X795593Y206063D03*
X777953Y256300D03*
X781300Y207800D03*
X774803Y265749D03*
X737009Y240552D03*
X746457Y215355D03*
X737029Y215337D03*
X743279Y215364D03*
X740158Y215355D03*
X743279Y212196D03*
X741294Y208274D03*
X743008Y206059D03*
X765355Y240552D03*
X743307Y246850D03*
X762217Y240526D03*
X755880Y240563D03*
X749580D03*
X755869Y253149D03*
X762167Y246850D03*
X755907Y246851D03*
X749569Y246850D03*
X762168Y253149D03*
X749608Y253150D03*
X743282Y253161D03*
X755868Y265748D03*
X755882Y259461D03*
X762218Y259425D03*
X749582Y259461D03*
X743282D03*
X762181Y265762D03*
X749582Y265761D03*
X743282D03*
X743281Y240562D03*
X768480Y265762D03*
X768518Y259425D03*
X768467Y253149D03*
Y246850D03*
X771653Y246887D03*
X762205Y221654D03*
X784252D03*
X777953D03*
X790551D03*
X740158D03*
X755906D03*
X746457D03*
X793701Y234254D03*
X781127Y246863D03*
X793672Y240560D03*
X796821Y246859D03*
X793701Y227954D03*
X796850Y221654D03*
X793674Y265758D03*
X793699Y262634D03*
X768504Y215355D03*
X763963Y331837D03*
X766437Y329363D03*
X748737Y330263D03*
X740157Y297243D03*
X737008Y297244D03*
X740158Y284646D03*
X744881Y309000D03*
X743306Y297243D03*
X790526Y300406D03*
X765369Y281474D03*
X771669D03*
X781120Y284665D03*
X759070Y281514D03*
X749816Y303716D03*
X777790Y304778D03*
X769768Y304464D03*
X759208Y304284D03*
X784252Y268885D03*
X796839Y290934D03*
X787438Y275197D03*
X796832Y272064D03*
X796875Y304331D03*
X796862Y281522D03*
X784249Y281464D03*
X787426Y272060D03*
X790551Y278384D03*
X743308Y284646D03*
X746457D03*
X737009D03*
X744400Y322800D03*
X746456Y297243D03*
X765353Y287794D03*
X771653D03*
X777952D03*
X784251D03*
X762225Y297227D03*
X755898Y287804D03*
X743283Y272060D03*
X755882D03*
X749581D03*
X746456Y290944D03*
X740157D03*
X793700Y297243D03*
X796849D03*
X790545Y290959D03*
X793694D03*
X793703Y287797D03*
X796839Y287784D03*
X793675Y284637D03*
X793679Y281508D03*
X793675Y278357D03*
X796868Y278364D03*
X793737Y275196D03*
X793682Y272064D03*
X793683Y268879D03*
X796850Y268910D03*
X763081Y350437D03*
X765555Y347963D03*
X775181Y338437D03*
X777655Y335963D03*
X780263Y350737D03*
X782737Y348263D03*
X792163Y338937D03*
X794637Y336463D03*
X746263Y332737D03*
X752363Y343737D03*
X754837Y341263D03*
X790357Y377781D03*
X735300Y401957D03*
X774700Y483600D03*
X782000Y505600D03*
X771184Y514916D03*
X745700Y498250D03*
X742300Y498200D03*
X759000Y482900D03*
X759169Y497414D03*
X750600Y497400D03*
X759200Y508000D03*
X777600Y512200D03*
X781700Y510900D03*
X736600Y500000D03*
X780750Y496750D03*
X781050Y492550D03*
X753099Y530282D03*
X795922Y531500D03*
X747200Y611900D03*
X802786Y57150D03*
X841300Y54200D03*
X818785Y50692D03*
X803000Y117100D03*
X813349Y73142D03*
X809349Y73197D03*
X821962Y189277D03*
X801385Y183067D03*
X801340Y179597D03*
X831504Y199129D03*
X840591Y264609D03*
X834791Y258109D03*
X831609Y261291D03*
X834127Y248490D03*
X830945Y251672D03*
X832148Y204444D03*
X816900Y231700D03*
X803160Y259454D03*
X803150Y256336D03*
X807177Y261023D03*
X814262Y218950D03*
X810277Y243190D03*
X810688Y238944D03*
X803129Y240535D03*
X803158Y237414D03*
X806862Y243302D03*
X806918Y237804D03*
X826000Y233400D03*
X828000Y243100D03*
X851591Y310409D03*
X848409Y313591D03*
X856091Y294909D03*
X852909Y298091D03*
X850091Y288909D03*
X846909Y292091D03*
X846591Y270409D03*
X843409Y273591D03*
X844591Y283409D03*
X841409Y286591D03*
X837409Y267791D03*
X822817Y331022D03*
X810079Y271264D03*
X809968Y290464D03*
X808400Y300900D03*
X812164Y279674D03*
X811600Y317300D03*
X802363Y336637D03*
X804837Y334163D03*
X820343Y333496D03*
X817700Y385700D03*
X806400Y398700D03*
X810100Y404934D03*
X857000Y410600D03*
X850950Y489300D03*
X804584Y526584D03*
X829500Y481500D03*
X883240Y301973D03*
X888668Y322100D03*
X886540Y388996D03*
G54D25*
X201801Y684252D03*
X225601D03*
G54D38*
X651575Y20039D03*
X608267D03*
X641732Y126811D03*
X624015D03*
X651575Y72441D03*
X608267D03*
X730315Y20039D03*
X687007D03*
X720472Y126811D03*
X702755D03*
X730315Y72441D03*
X687007D03*
G54D32*
X421653Y130709D03*
X428740Y125985D03*
X435827Y130709D03*
X442913Y125985D03*
X450000Y130709D03*
X457086Y125985D03*
X464173Y130709D03*
X471260Y125985D03*
X428740Y131496D03*
X442913D03*
X457086D03*
X471260D03*
X421653Y136221D03*
X435827D03*
X450000D03*
X464173D03*
X421653Y144882D03*
X428740Y140158D03*
X435827Y144882D03*
X442913Y140158D03*
X450000Y144882D03*
X457086Y140158D03*
X464173Y144882D03*
X471260Y140158D03*
X421653Y150394D03*
X428740Y145670D03*
X435827Y150394D03*
X442913Y145670D03*
X450000Y150394D03*
X457086Y145670D03*
X464173Y150394D03*
X471260Y145670D03*
X421653Y159055D03*
X428740Y154331D03*
X435827Y159055D03*
X442913Y154331D03*
X450000Y159055D03*
X457086Y154331D03*
X464173Y159055D03*
X471260Y154331D03*
X421653Y164567D03*
X428740Y159843D03*
X435827Y164567D03*
X442913Y159843D03*
X450000Y164567D03*
X457086Y159843D03*
X464173Y164567D03*
X471260Y159843D03*
X421653Y173229D03*
X428740Y168504D03*
X435827Y173229D03*
X442913Y168504D03*
X450000Y173229D03*
X457086Y168504D03*
X464173Y173229D03*
X471260Y168504D03*
X421653Y178740D03*
X428740Y174016D03*
X435827Y178740D03*
X442913Y174016D03*
X450000Y178740D03*
X457086Y174016D03*
X464173Y178740D03*
X471260Y174016D03*
X506693Y130709D03*
X513779Y125985D03*
X520866Y130709D03*
X527953Y125985D03*
X535039Y130709D03*
X513779Y131496D03*
X527953D03*
X506693Y136221D03*
X520866D03*
X535039D03*
X506693Y144882D03*
X513779Y140158D03*
X520866Y144882D03*
X527953Y140158D03*
X535039Y144882D03*
X506693Y150394D03*
X513779Y145670D03*
X520866Y150394D03*
X527953Y145670D03*
X535039Y150394D03*
X506693Y159055D03*
X513779Y154331D03*
X520866Y159055D03*
X527953Y154331D03*
X535039Y159055D03*
X506693Y164567D03*
X513779Y159843D03*
X520866Y164567D03*
X527953Y159843D03*
X535039Y164567D03*
X506693Y173229D03*
X513779Y168504D03*
X520866Y173229D03*
X527953Y168504D03*
X535039Y173229D03*
X506693Y178740D03*
X513779Y174016D03*
X520866Y178740D03*
X527953Y174016D03*
X535039Y178740D03*
X542126Y125985D03*
X549212Y130709D03*
X556299Y125985D03*
X542126Y131496D03*
X556299D03*
X549212Y136221D03*
X542126Y140158D03*
X549212Y144882D03*
X556299Y140158D03*
X542126Y145670D03*
X549212Y150394D03*
X556299Y145670D03*
X542126Y154331D03*
X549212Y159055D03*
X556299Y154331D03*
X542126Y159843D03*
X549212Y164567D03*
X556299Y159843D03*
X542126Y168504D03*
X549212Y173229D03*
X556299Y168504D03*
X542126Y174016D03*
X549212Y178740D03*
X556299Y174016D03*
X638780Y69685D03*
X629921D03*
X621063D03*
X638780Y114567D03*
X635827Y120079D03*
X629921Y114567D03*
X626969Y120079D03*
X621063Y114567D03*
X618110Y120079D03*
X638780Y99606D03*
X635827Y105118D03*
X629921Y99606D03*
X621063D03*
X626969Y105118D03*
X618110D03*
X638780Y84646D03*
X635827Y90157D03*
X626969D03*
X629921Y84646D03*
X621063D03*
X618110Y90157D03*
X635827Y75197D03*
X626969D03*
X618110D03*
X717520Y69685D03*
X708661D03*
X699803D03*
X717520Y114567D03*
X714567Y120079D03*
X708661Y114567D03*
X705709Y120079D03*
X699803Y114567D03*
X696850Y120079D03*
X717520Y99606D03*
X714567Y105118D03*
X708661Y99606D03*
X699803D03*
X705709Y105118D03*
X696850D03*
X717520Y84646D03*
X714567Y90157D03*
X705709D03*
X708661Y84646D03*
X699803D03*
X696850Y90157D03*
X714567Y75197D03*
X705709D03*
X696850D03*
G54D29*
X305906Y388386D03*
G54D20*
X75534Y625175D03*
X75300Y679300D03*
Y674300D03*
X78370Y724300D03*
Y719500D03*
X80334Y625175D03*
X81300Y675100D03*
Y680100D03*
X134223Y691027D03*
X83170Y724300D03*
Y719500D03*
X122435Y666782D03*
Y661982D03*
X155400Y717700D03*
X249500Y719500D03*
Y724300D03*
Y729100D03*
Y733900D03*
Y738700D03*
X321382Y197574D03*
X296282Y189224D03*
Y184424D03*
X301082D03*
Y189224D03*
X335132Y195874D03*
X305862Y210014D03*
X334882Y215874D03*
Y220874D03*
X321382Y202374D03*
X335132Y205974D03*
X322586Y653754D03*
X317786D03*
X312986D03*
X308186D03*
X305500Y721000D03*
X310500D03*
X304150Y674700D03*
X299350D03*
X305500Y726000D03*
X310500D03*
X521634Y38901D03*
Y34101D03*
X516834Y38901D03*
Y34101D03*
X526434Y43701D03*
X521634D03*
X516834D03*
X520000Y63400D03*
X515200Y66440D03*
X520585Y68348D03*
X508668Y79607D03*
X503550Y79500D03*
X511100Y75060D03*
X506100D03*
X511100Y70060D03*
X525200Y71440D03*
X516628Y71806D03*
X600700Y35700D03*
X595500Y35600D03*
X595700Y29800D03*
X600900Y29700D03*
X576512Y369625D03*
Y364825D03*
X581312Y369625D03*
Y364825D03*
X609200Y330400D03*
X642700Y454400D03*
X642500Y449100D03*
X642600Y459500D03*
X621600Y486619D03*
X626958Y486419D03*
X642500Y464700D03*
X629500Y482500D03*
Y477000D03*
Y471500D03*
X635000Y482500D03*
Y476500D03*
Y471000D03*
X657000Y555000D03*
X662000D03*
X661887Y560010D03*
X656887D03*
X708483Y311988D03*
X713283D03*
X723900Y326350D03*
X718940Y326270D03*
X714900Y453600D03*
X715200Y459600D03*
X706700Y413900D03*
X710200Y417400D03*
Y422900D03*
Y427900D03*
X698700Y417600D03*
Y423100D03*
Y428100D03*
X676000Y431000D03*
X671000D03*
Y421000D03*
X676000D03*
X671000Y426000D03*
X676000D03*
X715200Y465000D03*
X689500Y518500D03*
Y524000D03*
X694738Y523940D03*
X694690Y519034D03*
X687015Y658100D03*
Y653300D03*
Y648500D03*
Y643700D03*
Y682100D03*
X673950Y686104D03*
Y691104D03*
Y696104D03*
Y701104D03*
Y706104D03*
X687015Y677300D03*
Y672500D03*
Y667700D03*
Y662900D03*
X754000Y172700D03*
Y177500D03*
X798359Y351659D03*
X795193Y355540D03*
X791786Y359001D03*
X750000Y427100D03*
X754800D03*
X783800Y436000D03*
X779000D03*
X793400D03*
X788600D03*
X788400Y427100D03*
X783600D03*
X778800D03*
X774200Y436000D03*
X774000Y427100D03*
X769200D03*
X764400D03*
X759600D03*
X826993Y358840D03*
X821502Y358356D03*
X827145Y363638D03*
X821653Y363488D03*
X826900Y332500D03*
X825300Y339900D03*
X825100Y347300D03*
X828100Y352900D03*
X809792Y379122D03*
X814592D03*
X809792Y374322D03*
X814592D03*
X842900Y347200D03*
X840800Y352800D03*
X804300Y436500D03*
X813900D03*
X809100D03*
X818700D03*
X823500D03*
X827000Y516000D03*
X832000D03*
Y521000D03*
X827000D03*
X843900Y464000D03*
X848700Y465200D03*
Y470600D03*
X881147Y394517D03*
X880887Y399474D03*
G54D35*
X564803Y24409D03*
X584803D03*
X753780D03*
X773780D03*
X801024D03*
X821024D03*
G54D23*
X197243Y589764D03*
X203542Y592913D03*
X168898Y548819D03*
X172000Y577150D03*
X209841Y574016D03*
X206692D03*
X165745Y564567D03*
X168895D03*
X159449Y561417D03*
X165748D03*
X172047D03*
X162598Y558268D03*
X168898D03*
X165748Y555118D03*
X159449D03*
X168898Y567717D03*
X159449Y570866D03*
X168898Y583464D03*
Y577165D03*
X159449Y586614D03*
X162598Y580315D03*
Y586614D03*
X165748D03*
X168898D03*
X159449Y577165D03*
X156299D03*
X168898Y580315D03*
X159449D03*
X162598Y577165D03*
X165748Y580315D03*
X162598Y583464D03*
X165748Y570866D03*
Y567717D03*
X162598D03*
X172047Y570866D03*
X162597Y555118D03*
X197243Y551970D03*
X194093D03*
X200395Y555120D03*
X181497Y551970D03*
Y589764D03*
X187795Y555120D03*
X206692Y564569D03*
Y561419D03*
Y558269D03*
Y567718D03*
X203543Y574017D03*
X206692Y583465D03*
X194093Y586614D03*
X178347Y551970D03*
X175197D03*
Y558268D03*
X178347Y589764D03*
X190945Y542519D03*
X172047Y545669D03*
Y551970D03*
X159449Y545671D03*
X162599Y545669D03*
X165749D03*
X184646Y548821D03*
Y545671D03*
X209842Y567717D03*
X184645Y542519D03*
X206692Y542521D03*
X209841Y577165D03*
X159449Y542521D03*
X156299Y545671D03*
X168898Y592913D03*
X181497Y545671D03*
X209842Y545669D03*
X165749Y548819D03*
X175197Y545671D03*
X162599Y542519D03*
X168898D03*
X156299Y542521D03*
X181496Y542520D03*
X159449Y548821D03*
X206692Y589763D03*
X172047Y548819D03*
X168898Y551969D03*
X162599Y548821D03*
X194093Y589764D03*
Y592913D03*
X162598Y561417D03*
X168898Y555119D03*
X181497Y548821D03*
X178346Y545670D03*
X206692Y586614D03*
X209842Y586613D03*
X209841Y592913D03*
X162595Y564567D03*
X162598Y570866D03*
X203542Y548821D03*
Y586614D03*
Y580315D03*
X178344Y577166D03*
X178346Y586615D03*
X181497Y586614D03*
X178347Y574018D03*
Y570868D03*
X190944Y586614D03*
X200394Y570866D03*
Y574016D03*
X203543Y561418D03*
Y564568D03*
X165748Y551968D03*
X159448D03*
X178346Y555119D03*
X178347Y564569D03*
X197245Y555118D03*
X190944D03*
X181497Y555120D03*
X172048Y564569D03*
X172047Y567717D03*
X175298Y577266D03*
X209842Y558268D03*
X190944Y589764D03*
Y592913D03*
X197244Y586615D03*
X200393Y586614D03*
X194094Y542519D03*
X209842Y564567D03*
X200393Y548819D03*
X209842Y561417D03*
Y589763D03*
X206692Y580315D03*
X209841D03*
X200393Y545669D03*
X206692Y545671D03*
X200393Y592913D03*
X159448Y589764D03*
Y592913D03*
X162598Y589764D03*
X165748D03*
Y592913D03*
X165749Y542519D03*
X175197Y592913D03*
X172048D03*
X209842Y555119D03*
Y551969D03*
X181497Y592913D03*
X197244Y545669D03*
X194094Y548820D03*
X209842Y548819D03*
X175197Y548821D03*
X168898Y545669D03*
X156300Y539371D03*
X194094Y545669D03*
X197244Y542520D03*
X194094Y602362D03*
X206692Y596063D03*
X194093D03*
X209841D03*
X190945Y599213D03*
X190944Y596063D03*
X187796Y599212D03*
X184645Y599213D03*
X159448Y596063D03*
X168898D03*
X203542Y602362D03*
Y599213D03*
X206692Y602362D03*
X203542Y596063D03*
X194094Y599213D03*
X162598Y596063D03*
X165748Y599213D03*
X168898D03*
X162598D03*
X159448D03*
X172048Y596063D03*
X178346Y596064D03*
X178347Y599213D03*
X181496Y596062D03*
X209841Y599212D03*
X206692Y599213D03*
X165748Y596063D03*
X175197D03*
Y599213D03*
X172048D03*
X219800Y445700D03*
X213874Y445226D03*
X216141Y580315D03*
Y577165D03*
X212991Y567718D03*
X216141Y583465D03*
Y586614D03*
Y564569D03*
X212992Y561417D03*
X216141Y567718D03*
X219293Y567717D03*
X212992Y580315D03*
X212991Y577165D03*
Y574016D03*
X216141D03*
Y561419D03*
X212991Y583465D03*
Y542519D03*
X212992Y589764D03*
Y555119D03*
Y558268D03*
X216142Y548820D03*
X216141Y555120D03*
Y558269D03*
X222441Y548820D03*
X219291D03*
X212992Y551969D03*
X216141Y551970D03*
X212992Y548819D03*
X216141Y589762D03*
X212993Y592912D03*
X212992Y564567D03*
Y545669D03*
X216142D03*
X212992Y602363D03*
X212991Y599212D03*
X216141D03*
X781088Y294094D03*
X771653Y294093D03*
X777952Y290944D03*
X777989Y294093D03*
X774802Y290944D03*
X774835Y294088D03*
X768503Y290944D03*
X768498Y294124D03*
X765353Y290944D03*
X765325Y294102D03*
X759054Y290944D03*
X759055Y294094D03*
X755905Y290944D03*
Y294093D03*
X787401Y290944D03*
X787408Y294074D03*
X784251Y290944D03*
X784258Y294064D03*
G54D30*
X346457Y66850D03*
X353543Y70787D03*
Y62913D03*
Y55039D03*
X346457Y74724D03*
Y84567D03*
X353543Y86535D03*
Y78661D03*
G54D28*
X305906Y182874D03*
G54D11*
X80708Y44292D03*
X61024Y34449D03*
X33464D03*
X38386Y24606D03*
X108268Y44292D03*
X85630Y34449D03*
X600300Y574400D03*
X610300D03*
G54D19*
X67853Y573865D03*
X96800Y662000D03*
X90200Y667100D03*
X85400D03*
X91700Y744800D03*
X96500D03*
X101300D03*
X106100D03*
X110900D03*
X115700D03*
X120500D03*
X125300D03*
X187795Y570866D03*
X190944Y574016D03*
X304231Y261048D03*
X334582Y291284D03*
Y279784D03*
X307567Y324092D03*
X304267Y322892D03*
Y311392D03*
X307567Y310292D03*
Y298792D03*
X304267Y297692D03*
Y286192D03*
X334582Y330271D03*
X328182Y329174D03*
Y317674D03*
X334582Y316574D03*
Y305074D03*
X328182Y303977D03*
Y292477D03*
X307567Y285092D03*
Y273592D03*
X304231Y272548D03*
X304267Y373292D03*
Y361792D03*
X307567Y360692D03*
Y349192D03*
X304267Y348092D03*
Y336592D03*
X307567Y335592D03*
X328182Y379518D03*
Y368018D03*
X334582Y366974D03*
Y355474D03*
Y341771D03*
X328182Y354371D03*
Y342871D03*
X335200Y640100D03*
X330400D03*
X335000Y615400D03*
X335300Y609800D03*
X335000Y621200D03*
X325600Y640100D03*
X315520Y711720D03*
X325700Y711600D03*
X320320Y711720D03*
X628160Y569095D03*
X619400Y570451D03*
X721260Y272047D03*
X700546Y577599D03*
X691796D03*
X691296Y572599D03*
X705696D03*
X696296Y577599D03*
X709296Y572599D03*
Y577599D03*
X702096Y572599D03*
X694896D03*
X698496D03*
X704796Y577599D03*
X709569Y582496D03*
X698769D03*
X695169D03*
X691569D03*
X702369D03*
X705969D03*
X777550Y62350D03*
X737009Y237400D03*
X759073Y287810D03*
X740159Y278345D03*
X798000Y459300D03*
X751100Y405400D03*
X755900D03*
X760700D03*
X765500D03*
X770300D03*
X775100D03*
X790600Y458000D03*
X781000D03*
X785800D03*
X776200D03*
X789500Y405400D03*
X784700D03*
X779900D03*
X828000Y459300D03*
X823200D03*
X832800D03*
X818400D03*
X807600D03*
X802800D03*
X812400D03*
X830100Y501500D03*
X839700D03*
X834900D03*
G54D10*
X8500Y18279D03*
Y28279D03*
Y38279D03*
Y48279D03*
Y58279D03*
Y68279D03*
X13721Y8500D03*
X8500Y13279D03*
Y23279D03*
Y33279D03*
Y43279D03*
Y53279D03*
Y63279D03*
Y78279D03*
Y88279D03*
Y98279D03*
Y108279D03*
Y118279D03*
Y128279D03*
Y73279D03*
Y83279D03*
Y93279D03*
Y103279D03*
Y113279D03*
Y123279D03*
Y133279D03*
Y138279D03*
Y148279D03*
Y158279D03*
Y168279D03*
Y178279D03*
Y188279D03*
Y198279D03*
Y143279D03*
Y153279D03*
Y163279D03*
Y173279D03*
Y183279D03*
Y193279D03*
Y208279D03*
Y218279D03*
Y228279D03*
Y238279D03*
Y248279D03*
Y258279D03*
Y203279D03*
Y213279D03*
Y223279D03*
Y233279D03*
Y243279D03*
Y253279D03*
Y263279D03*
Y268279D03*
Y278279D03*
Y288279D03*
Y298279D03*
Y308279D03*
Y318279D03*
Y328279D03*
Y273279D03*
Y283279D03*
Y293279D03*
Y303279D03*
Y313279D03*
Y323279D03*
Y338279D03*
Y348279D03*
Y358279D03*
Y368279D03*
Y378279D03*
Y388279D03*
Y333279D03*
Y343279D03*
Y353279D03*
Y363279D03*
Y373279D03*
Y383279D03*
Y393279D03*
Y398279D03*
Y408279D03*
Y418279D03*
Y428279D03*
Y438279D03*
Y448279D03*
Y458279D03*
Y403279D03*
Y413279D03*
Y423279D03*
Y433279D03*
Y443279D03*
Y453279D03*
Y468279D03*
Y478279D03*
Y488279D03*
Y498279D03*
Y508279D03*
Y518279D03*
Y528279D03*
Y463279D03*
Y473279D03*
Y483279D03*
Y493279D03*
Y503279D03*
Y513279D03*
Y523279D03*
Y538279D03*
Y548279D03*
Y558279D03*
Y568279D03*
Y578279D03*
Y588279D03*
Y533279D03*
Y543279D03*
Y553279D03*
Y563279D03*
Y573279D03*
Y583279D03*
Y593279D03*
Y598279D03*
Y608279D03*
Y618279D03*
Y628279D03*
Y638279D03*
Y648279D03*
Y658279D03*
Y603279D03*
Y613279D03*
Y623279D03*
Y633279D03*
Y643279D03*
Y653279D03*
Y668279D03*
Y678279D03*
Y688279D03*
Y698279D03*
Y708279D03*
Y718279D03*
Y663279D03*
Y673279D03*
Y683279D03*
Y693279D03*
Y703279D03*
Y713279D03*
X8892Y723187D03*
X11090Y727806D03*
X13500Y732400D03*
X78721Y8500D03*
X68721D03*
X58721D03*
X48721D03*
X38721D03*
X28721D03*
X18721D03*
X73721D03*
X53721D03*
X43721D03*
X33721D03*
X23721D03*
X77780Y61790D03*
X73760Y67930D03*
X56960Y58900D03*
X54050Y63260D03*
X43510Y57810D03*
X29890Y54070D03*
X49460Y63690D03*
X68730Y67930D03*
X63721Y8500D03*
X37660Y566400D03*
X42597Y571789D03*
X64701Y570716D03*
Y564416D03*
X61100Y546700D03*
X64400Y539000D03*
X64884Y650984D03*
X50700Y664000D03*
X50800Y667900D03*
X65900Y671000D03*
X65700Y660900D03*
X70600Y665800D03*
X60700Y665900D03*
X70800Y660700D03*
X60800Y660900D03*
X70700Y671000D03*
X60600Y670900D03*
X65714Y665850D03*
X40309Y660700D03*
X71850Y698900D03*
X28100Y755600D03*
X33100D03*
X69057Y755280D03*
X74057D03*
X20300Y746200D03*
X15800Y736900D03*
X18100Y741500D03*
X22600Y750800D03*
X79057Y755280D03*
X108721Y8500D03*
X98721D03*
X88721D03*
X112197Y65406D03*
Y60406D03*
Y55406D03*
X103721Y8500D03*
X93721D03*
X83721D03*
X84610Y64470D03*
X98770Y60860D03*
X112197Y75406D03*
Y85406D03*
Y95406D03*
Y105406D03*
Y115406D03*
Y120406D03*
Y110406D03*
Y100406D03*
Y90406D03*
Y80406D03*
Y70406D03*
Y145406D03*
Y195406D03*
Y185406D03*
Y175406D03*
Y165406D03*
Y155406D03*
Y200406D03*
Y190406D03*
Y180406D03*
Y170406D03*
Y160406D03*
Y150406D03*
Y265406D03*
Y255406D03*
Y245406D03*
Y235406D03*
Y225406D03*
Y215406D03*
Y205406D03*
Y260406D03*
Y250406D03*
Y240406D03*
Y230406D03*
Y220406D03*
Y210406D03*
Y325406D03*
Y315406D03*
Y305406D03*
Y295406D03*
Y285406D03*
Y275406D03*
Y330406D03*
Y320406D03*
Y310406D03*
Y300406D03*
Y290406D03*
Y280406D03*
Y270406D03*
Y390406D03*
Y380406D03*
Y370406D03*
Y360406D03*
Y350406D03*
Y395406D03*
Y385406D03*
Y375406D03*
Y365406D03*
Y355406D03*
Y345406D03*
Y335406D03*
Y340406D03*
Y420406D03*
Y410406D03*
Y400406D03*
Y425406D03*
Y415406D03*
Y405406D03*
X107100Y497300D03*
X138900Y525999D03*
X135012Y510200D03*
X119400Y511500D03*
X133152Y484074D03*
X105350Y511850D03*
X94473Y547093D03*
X89901Y587466D03*
X136990Y535235D03*
X103600Y637800D03*
X103500Y645500D03*
Y650535D03*
X101400Y606300D03*
X97800D03*
X137210Y622030D03*
X134030Y620760D03*
X130630Y620900D03*
X101500Y597000D03*
X85500Y628500D03*
X122750Y616950D03*
X122000Y628700D03*
X144800Y657900D03*
X136100Y656300D03*
X125100Y656700D03*
X86500Y703100D03*
X86600Y708300D03*
X111300Y705500D03*
X135019Y706095D03*
X130019D03*
X139916Y705822D03*
X130019Y724095D03*
X135019Y714845D03*
Y719095D03*
Y723595D03*
Y710595D03*
X130019Y720495D03*
Y716895D03*
Y713295D03*
Y709695D03*
X139916Y723822D03*
Y720222D03*
Y716622D03*
Y713022D03*
Y709422D03*
X144057Y755280D03*
X134057D03*
X124057D03*
X114057D03*
X104057D03*
X94057D03*
X84057D03*
X89057D03*
X99057D03*
X109057D03*
X119057D03*
X129057D03*
X139057D03*
X146301Y460200D03*
X146263Y468562D03*
X203307Y506400D03*
X203500Y513500D03*
X207500Y503000D03*
X191418Y509981D03*
X170870Y492270D03*
X158000Y480700D03*
X146143Y481057D03*
X184646Y577165D03*
X187795D03*
X190945D03*
X187795Y574016D03*
X184646D03*
Y570866D03*
X187795Y564567D03*
X194094Y567716D03*
X190945D03*
X187795D03*
X184646D03*
X195300Y529400D03*
X156297Y558267D03*
X171020Y611020D03*
X200610Y639611D03*
X207900Y645600D03*
X169000Y640300D03*
X184967Y643983D03*
X200560Y635100D03*
X170940Y614400D03*
X191110Y611050D03*
X196855Y698355D03*
X208300Y704985D03*
X203500D03*
X198700D03*
X151130Y703440D03*
X193900Y704985D03*
X191766Y679920D03*
X202800Y660900D03*
X189000Y659900D03*
X204057Y755280D03*
X194057D03*
X184057D03*
X174057D03*
X164057D03*
X154057D03*
X149057D03*
X159057D03*
X169057D03*
X179057D03*
X189057D03*
X199057D03*
X209057D03*
X275500Y466200D03*
X211700Y513500D03*
X220100Y513400D03*
X211196Y487762D03*
X222600Y503500D03*
X246000Y516670D03*
X222500Y536161D03*
X211500Y529400D03*
X230900Y581600D03*
X229800Y593200D03*
X247400Y589600D03*
X252593Y547650D03*
X261900Y591300D03*
X247100Y582400D03*
X246611Y551511D03*
X246484Y537139D03*
X269900Y567619D03*
X255228Y631071D03*
X255648Y626127D03*
X245300Y635700D03*
X254199Y603443D03*
X254600Y597100D03*
X229137Y634881D03*
X266857Y634343D03*
X256001Y612347D03*
X258869Y603050D03*
X266571Y608619D03*
X275470Y608480D03*
X270400Y622870D03*
X264040Y648370D03*
X219200Y647200D03*
X221900Y630800D03*
X218800Y635600D03*
X230900Y649100D03*
X211706Y645349D03*
X247725Y656375D03*
X246500Y601500D03*
X234000Y629576D03*
X218200Y651400D03*
X248450Y609900D03*
X266847Y626253D03*
X229063Y638560D03*
X216600Y658400D03*
X274800Y635000D03*
X222700Y704985D03*
X217900D03*
X213100D03*
X261248Y700086D03*
X272050Y711810D03*
X267880Y704920D03*
X262634Y711233D03*
X266400Y675349D03*
X265000Y662574D03*
X247825Y670375D03*
X235100Y679921D03*
X221575Y695400D03*
X242000Y693400D03*
X274057Y755280D03*
X264057D03*
X254057D03*
X244057D03*
X234057D03*
X224057D03*
X214057D03*
X219057D03*
X229057D03*
X239057D03*
X249057D03*
X259057D03*
X269057D03*
X315120Y8500D03*
X310120D03*
X305120D03*
X300120D03*
X296020Y9420D03*
Y14420D03*
Y19420D03*
Y24420D03*
Y29420D03*
X340297Y117548D03*
X341484Y110328D03*
X322426Y223731D03*
Y227531D03*
X321197Y254433D03*
X322426Y231331D03*
X321782Y215974D03*
X306446Y247874D03*
X305382Y227474D03*
X305498Y213824D03*
X305703Y202165D03*
X306407Y206057D03*
X321281Y266486D03*
X321432Y279090D03*
X321882Y291874D03*
Y304374D03*
X321432Y316885D03*
Y329484D03*
Y342082D03*
Y354681D03*
X321202Y376887D03*
X321432Y367279D03*
X335982Y390874D03*
X307364Y505750D03*
X321976D03*
X329035Y519325D03*
X293793Y521556D03*
X321208Y519411D03*
X285800Y549394D03*
X303100Y587000D03*
X292850Y586100D03*
X293271Y557248D03*
X327110Y583660D03*
X316680Y583527D03*
X337899Y587874D03*
X285982Y542502D03*
X310350Y538293D03*
X330860Y551744D03*
X325447Y536109D03*
X339081Y628173D03*
X290300Y636900D03*
X290500Y640600D03*
X331655Y603405D03*
X339822Y609785D03*
X339847Y620281D03*
X305470Y623734D03*
X278546Y633450D03*
X281900Y640900D03*
X306486Y643750D03*
X306286Y633650D03*
X311186Y638550D03*
X301286Y638650D03*
X311386Y633450D03*
X301386Y633650D03*
X311286Y643750D03*
X301186Y643650D03*
X306300Y638600D03*
X317600Y603300D03*
X339266Y658409D03*
X318400Y678400D03*
X325900Y678500D03*
X330200Y709300D03*
X334650Y689700D03*
X335350Y684650D03*
X281400Y708200D03*
X281500Y712200D03*
X279400Y686400D03*
X294804Y695204D03*
X295634Y710070D03*
X290520Y715120D03*
X300620Y715220D03*
X290720Y705120D03*
X300720Y704920D03*
X290620Y710120D03*
X300520Y710020D03*
X295620Y705120D03*
X295820Y715220D03*
X296800Y665081D03*
X311600Y670354D03*
X319600Y670450D03*
X293300Y679700D03*
X334057Y755280D03*
X324057D03*
X314057D03*
X304057D03*
X294057D03*
X284057D03*
X279057D03*
X289057D03*
X299057D03*
X309057D03*
X319057D03*
X329057D03*
X339057D03*
X298570Y743670D03*
X306470Y743570D03*
X278553Y740020D03*
X380500Y33500D03*
Y30000D03*
X384000D03*
X381173Y49058D03*
X381156Y54116D03*
X375200Y63400D03*
X375300Y72150D03*
X374844Y87900D03*
X375000Y107300D03*
X393206Y77614D03*
X374844Y76700D03*
X362000Y124000D03*
X349072Y193574D03*
X400212Y154732D03*
X400351Y165605D03*
X349072Y189774D03*
X371775Y200577D03*
X348082Y186224D03*
X362197Y222068D03*
X362722Y237674D03*
X369000Y512700D03*
X345497Y527644D03*
X355300Y510100D03*
X353300Y521400D03*
X344700Y509000D03*
X368721Y525271D03*
X371900Y481548D03*
X365800Y498300D03*
X373500Y540305D03*
X393912Y568499D03*
X351600Y540600D03*
X348314Y585614D03*
X385600Y529107D03*
X372600Y576207D03*
X374292Y580300D03*
X355012Y582324D03*
X363008Y547309D03*
X371227Y566830D03*
X348600Y643500D03*
X344564Y628104D03*
X379400Y641800D03*
X385163Y641354D03*
X342133Y603008D03*
X391150Y613429D03*
X350500Y647600D03*
X355000Y652160D03*
X374200Y645871D03*
X370200Y636400D03*
X359036Y635900D03*
X359258Y596820D03*
X371400Y606400D03*
X358900Y612800D03*
X358800Y606300D03*
X365300Y606500D03*
X371400Y612700D03*
X371300Y618800D03*
X365500Y619000D03*
X358900Y618800D03*
X365164Y612620D03*
X383300Y600600D03*
X384410Y633530D03*
X354102Y660666D03*
X392720Y697500D03*
X376342Y711260D03*
X358296Y672460D03*
X346465Y703185D03*
X364200Y713100D03*
X369600Y693400D03*
X351100Y712100D03*
X381638Y755280D03*
X384809Y752321D03*
X387045Y747849D03*
X389281Y743376D03*
X391517Y738904D03*
X393753Y734432D03*
X395989Y729960D03*
X398225Y725488D03*
X344057Y755280D03*
X468000Y35400D03*
X464000Y35500D03*
X468000Y39500D03*
Y31500D03*
X472000Y35500D03*
X439200Y22100D03*
X439549Y26339D03*
X439554Y30429D03*
X439302Y34040D03*
X506970Y18693D03*
X502830D03*
X496035Y46435D03*
X536794Y77373D03*
X531664Y78463D03*
X515915Y80576D03*
X520310Y76700D03*
X559200Y36265D03*
X552540Y64530D03*
X577100Y78600D03*
X545300Y75600D03*
X568000Y70000D03*
X576610Y388416D03*
Y393416D03*
X601500Y363600D03*
X576610Y398416D03*
Y403416D03*
Y408416D03*
Y413416D03*
Y418416D03*
Y423416D03*
Y428416D03*
Y433416D03*
Y438416D03*
Y443416D03*
Y448416D03*
Y453416D03*
Y458416D03*
Y463416D03*
Y468416D03*
Y473416D03*
Y478416D03*
Y483416D03*
Y488416D03*
Y493416D03*
Y498416D03*
Y503416D03*
Y508416D03*
Y513416D03*
Y518416D03*
Y523416D03*
Y528416D03*
Y533416D03*
Y538416D03*
Y543416D03*
Y548416D03*
Y553416D03*
Y558416D03*
Y563416D03*
Y568416D03*
Y573416D03*
Y578416D03*
Y583416D03*
Y588416D03*
Y593416D03*
Y598416D03*
Y603416D03*
Y608416D03*
Y613416D03*
Y618416D03*
Y623416D03*
Y628416D03*
Y633416D03*
Y638416D03*
Y643416D03*
Y648416D03*
Y653416D03*
Y658416D03*
Y663416D03*
Y668416D03*
Y673416D03*
Y678416D03*
Y683416D03*
Y688416D03*
Y693416D03*
Y698416D03*
Y703416D03*
Y708416D03*
Y713416D03*
Y718416D03*
X577063Y723309D03*
X579299Y727781D03*
X581535Y732253D03*
X583771Y736725D03*
X586007Y741198D03*
X588243Y745670D03*
X590479Y750142D03*
X592715Y754614D03*
X641732Y117323D03*
X632873D03*
X624015D03*
X641732Y102362D03*
X632873D03*
X624015D03*
X641732Y87402D03*
X632873D03*
X624015D03*
X641732Y72441D03*
X632873D03*
X624015D03*
X638470Y164470D03*
X634910Y169360D03*
X644100Y199850D03*
X630000Y169600D03*
X629500Y187500D03*
X666700Y205600D03*
X629400Y217300D03*
X648700Y292900D03*
X654670Y391494D03*
X616428Y379533D03*
X626772Y371336D03*
X612300Y344300D03*
X613480Y333710D03*
X629900Y339300D03*
X610300Y354800D03*
X658000Y431500D03*
Y409000D03*
Y414000D03*
Y426000D03*
Y420500D03*
X657900Y443200D03*
X655100Y436900D03*
X610000Y467500D03*
X609000Y473500D03*
Y478500D03*
Y483500D03*
X645200Y521900D03*
X650400Y517600D03*
X656400Y517500D03*
X661500Y517600D03*
X629200Y536040D03*
X629080Y539920D03*
X625500Y536100D03*
X615500Y529800D03*
X616710Y534500D03*
X610200Y555400D03*
X625300Y539900D03*
X653600Y540300D03*
X645300Y655200D03*
Y650400D03*
Y645600D03*
Y640800D03*
X655000Y705000D03*
Y700200D03*
Y695400D03*
Y690600D03*
X645300Y684000D03*
Y679200D03*
Y674400D03*
Y669600D03*
Y664800D03*
Y660000D03*
X655000Y685800D03*
X659722Y755280D03*
X649722D03*
X639722D03*
X634722D03*
X644722D03*
X654722D03*
X664722D03*
X720472Y117323D03*
X711613D03*
X702755D03*
X720472Y102362D03*
X711613D03*
X702755D03*
X720472Y87402D03*
X711613D03*
X702755D03*
X720472Y72441D03*
X711613D03*
X702755D03*
X722150Y174300D03*
X727150Y184550D03*
X722150D03*
X711150Y174300D03*
X716650Y184550D03*
X711150D03*
X705650D03*
X721261Y240551D03*
X721260Y234252D03*
X691600Y207600D03*
X721820Y315750D03*
X677300Y314900D03*
X681200D03*
X684400Y313400D03*
X688000Y313200D03*
X694675Y323900D03*
X708100Y331410D03*
X718340Y315800D03*
X731400Y362700D03*
X727000Y353000D03*
X712417Y352800D03*
X708300Y445800D03*
X728874Y470860D03*
X725366Y470722D03*
X677275Y485625D03*
X683583Y485841D03*
X702824Y476476D03*
X682400Y463400D03*
X670400Y565500D03*
Y560700D03*
Y555900D03*
Y551100D03*
Y546300D03*
Y541500D03*
Y536700D03*
X703440Y548820D03*
X710459Y554134D03*
X719626Y590829D03*
X722300Y608200D03*
X708600Y608500D03*
X729722Y755280D03*
X719722D03*
X709722D03*
X699722D03*
X689722D03*
X679722D03*
X669722D03*
X674722D03*
X684722D03*
X694722D03*
X704722D03*
X714722D03*
X724722D03*
X734722D03*
X780100Y8500D03*
X775100D03*
X770100D03*
X765100D03*
X760100D03*
X755100D03*
X750100D03*
X745100D03*
X787895D03*
X797895D03*
X792895D03*
X795832Y66750D03*
X787360Y35650D03*
X776300Y47600D03*
X761900Y81700D03*
X772700Y113000D03*
X794650Y86050D03*
X769710Y125150D03*
X766110Y125270D03*
X793957Y113436D03*
X761950Y126450D03*
X773200Y97600D03*
X749600Y199300D03*
X749400Y195600D03*
X753800Y181500D03*
X753400Y185400D03*
X741300Y185700D03*
X749455Y202200D03*
X790551Y284646D03*
X781100Y287800D03*
X780300Y309300D03*
X795026Y374556D03*
X799426Y374456D03*
X738465Y352935D03*
X735484Y429378D03*
Y434178D03*
Y462978D03*
Y458178D03*
Y453378D03*
Y448578D03*
Y443778D03*
Y438978D03*
X740300Y427100D03*
Y431900D03*
Y446300D03*
Y441500D03*
Y436700D03*
X794700Y505200D03*
X747125Y483924D03*
X743726Y483813D03*
X735484Y467778D03*
X755500Y492600D03*
X768500Y480000D03*
X740253Y483893D03*
X797323Y512162D03*
X757099Y530082D03*
X763809Y537191D03*
X782709Y537691D03*
X799722Y755280D03*
X789722D03*
X779722D03*
X769722D03*
X759722D03*
X749722D03*
X739722D03*
X744722D03*
X754722D03*
X764722D03*
X774722D03*
X784722D03*
X794722D03*
X807895Y8500D03*
X817895D03*
X827895D03*
X837895D03*
X847895D03*
X857895D03*
X862895D03*
X852895D03*
X842895D03*
X832895D03*
X822895D03*
X812895D03*
X802895D03*
X826925Y57425D03*
X802227Y208424D03*
X802246Y205826D03*
X804600Y210800D03*
X808400D03*
X810300Y326450D03*
X823250Y319350D03*
X814450Y306950D03*
X842600Y339400D03*
X841100Y332300D03*
X810946Y389734D03*
X811112Y393735D03*
X857581Y391433D03*
X851100Y407500D03*
X864727Y398458D03*
X861000Y410500D03*
X846000Y476100D03*
X810200Y494900D03*
X815100Y499800D03*
X805200Y499900D03*
X815300Y494700D03*
X805300Y494900D03*
X815200Y505000D03*
X805100Y504900D03*
X810214Y499850D03*
X810400Y505000D03*
X849050Y481050D03*
X809384Y484984D03*
X800800Y526900D03*
X821050Y533350D03*
X813150Y533450D03*
X849722Y755280D03*
X839722D03*
X829722D03*
X819722D03*
X809722D03*
X804722D03*
X814722D03*
X824722D03*
X834722D03*
X844722D03*
X854722D03*
X867895Y8500D03*
X877895D03*
X887895D03*
X897895D03*
X907895D03*
X916697Y19698D03*
Y29698D03*
Y39698D03*
Y49698D03*
Y59698D03*
Y69698D03*
Y64698D03*
Y54698D03*
Y44698D03*
Y34698D03*
Y24698D03*
Y14698D03*
X912895Y8500D03*
X902895D03*
X892895D03*
X882895D03*
X872895D03*
X916697Y79698D03*
Y89698D03*
Y99698D03*
Y109698D03*
Y119698D03*
Y129698D03*
Y134698D03*
Y124698D03*
Y114698D03*
Y104698D03*
Y94698D03*
Y84698D03*
Y74698D03*
Y139698D03*
Y149698D03*
Y159698D03*
Y169698D03*
Y179698D03*
Y189698D03*
Y199698D03*
Y194698D03*
Y184698D03*
Y174698D03*
Y164698D03*
Y154698D03*
Y144698D03*
Y209698D03*
Y219698D03*
Y229698D03*
Y239698D03*
Y249698D03*
Y259698D03*
Y264698D03*
Y254698D03*
Y244698D03*
Y234698D03*
Y224698D03*
Y214698D03*
Y204698D03*
X888551Y226649D03*
X882871Y243771D03*
X892449Y241249D03*
X886300Y221150D03*
X916697Y269698D03*
Y279698D03*
Y289698D03*
Y299698D03*
Y309698D03*
Y319698D03*
Y329698D03*
Y324698D03*
Y314698D03*
Y304698D03*
Y294698D03*
Y284698D03*
Y274698D03*
X896969Y301500D03*
X916697Y339698D03*
Y349698D03*
Y359698D03*
Y369698D03*
Y379698D03*
Y389698D03*
Y394698D03*
Y384698D03*
Y374698D03*
Y364698D03*
Y354698D03*
Y344698D03*
Y334698D03*
Y399698D03*
Y409698D03*
Y419698D03*
Y429698D03*
Y439698D03*
Y449698D03*
Y459698D03*
Y454698D03*
Y444698D03*
Y434698D03*
Y424698D03*
Y414698D03*
Y404698D03*
X874727Y398458D03*
X869727D03*
X872750Y403400D03*
X916697Y469698D03*
Y479698D03*
Y489698D03*
Y499698D03*
Y509698D03*
Y519698D03*
Y524698D03*
Y514698D03*
Y504698D03*
Y494698D03*
Y484698D03*
Y474698D03*
Y464698D03*
Y529698D03*
Y539698D03*
Y549698D03*
Y559698D03*
Y569698D03*
Y579698D03*
Y589698D03*
Y584698D03*
Y574698D03*
Y564698D03*
Y554698D03*
Y544698D03*
Y534698D03*
Y599698D03*
Y609698D03*
Y619698D03*
Y629698D03*
Y639698D03*
Y649698D03*
Y659698D03*
Y654698D03*
Y644698D03*
Y634698D03*
Y624698D03*
Y614698D03*
Y604698D03*
Y594698D03*
Y669698D03*
Y679698D03*
Y689698D03*
Y699698D03*
Y709698D03*
Y719698D03*
Y714698D03*
Y704698D03*
Y694698D03*
Y684698D03*
Y674698D03*
Y664698D03*
X914700Y726100D03*
X912436Y730603D03*
X910200Y735300D03*
X907564Y739747D03*
X905500Y744400D03*
X903192Y748791D03*
X900800Y753700D03*
X894722Y755280D03*
G54D34*
X488838Y164744D03*
G54D13*
X18700Y54650D03*
X209189Y37075D03*
Y383483D03*
X489331Y245605D03*
Y698924D03*
X901000Y21400D03*
X902500Y676000D03*
G54D33*
X488838Y137225D03*
G54D16*
X89764Y238386D03*
X309252Y413583D03*
G54D24*
X163189Y669291D03*
G54D37*
X629921Y57874D03*
X708661D03*
G54D39*
X652756Y180000D03*
X865353Y332598D03*
G54D27*
X339331Y91929D03*
X360669Y49803D03*
G54D22*
X90157Y413583D03*
X309055Y157677D03*
G54D15*
X70865Y98425D03*
Y472440D03*
X314960D03*
X405511Y39370D03*
X364173Y740157D03*
X612204Y433070D03*
Y740157D03*
X875984Y433070D03*
Y740157D03*
G54D21*
X49213D03*
X875985Y59055D03*
G54D17*
X34132Y521245D03*
X34175Y526969D03*
X28800Y549474D03*
X29158Y543855D03*
X29058Y538228D03*
X28782Y555119D03*
X29165Y532612D03*
X33697Y560866D03*
X71002Y577013D03*
X67852Y586463D03*
Y583313D03*
X132100Y493000D03*
X114070Y481948D03*
X179000Y499800D03*
X186735Y463748D03*
X175100Y477000D03*
X184645Y589764D03*
Y539370D03*
X187795Y592914D03*
Y602363D03*
X421653Y126378D03*
X435827D03*
X450000D03*
X464173D03*
X428740Y121654D03*
X442913D03*
X457086D03*
X471260D03*
X421653Y183071D03*
X435827D03*
X450000D03*
X464173D03*
X421653Y140551D03*
X428740Y135827D03*
X435827Y140551D03*
X442913Y135827D03*
X450000Y140551D03*
X457086Y135827D03*
X464173Y140551D03*
X471260Y135827D03*
X421653Y154725D03*
X428740Y150000D03*
X435827Y154725D03*
X442913Y150000D03*
X450000Y154725D03*
X457086Y150000D03*
X464173Y154725D03*
X471260Y150000D03*
X421653Y168898D03*
X428740Y164173D03*
X435827Y168898D03*
X442913Y164173D03*
X450000Y168898D03*
X457086Y164173D03*
X464173Y168898D03*
X471260Y164173D03*
X506693Y126378D03*
X520866D03*
X535039D03*
X513779Y121654D03*
X527953D03*
X506693Y183071D03*
X520866D03*
X535039D03*
X506693Y140551D03*
X513779Y135827D03*
X520866Y140551D03*
X527953Y135827D03*
X535039Y140551D03*
X506693Y154725D03*
X513779Y150000D03*
X520866Y154725D03*
X527953Y150000D03*
X535039Y154725D03*
X506693Y168898D03*
X513779Y164173D03*
X520866Y168898D03*
X527953Y164173D03*
X535039Y168898D03*
X549212Y126378D03*
X542126Y121654D03*
X556299D03*
X549212Y183071D03*
X542126Y135827D03*
X549212Y140551D03*
X556299Y135827D03*
X542126Y150000D03*
X549212Y154725D03*
X556299Y150000D03*
X542126Y164173D03*
X549212Y168898D03*
X556299Y164173D03*
X704579Y258164D03*
X730710Y256302D03*
X733858Y256299D03*
Y253149D03*
X730710Y253152D03*
X733859Y234253D03*
Y237403D03*
X730710D03*
Y234254D03*
X733858Y243700D03*
Y246849D03*
Y249999D03*
Y265747D03*
X730710Y240553D03*
Y243702D03*
Y246852D03*
Y250002D03*
Y265750D03*
X721295Y221651D03*
X718089Y243684D03*
X721260Y253150D03*
Y259449D03*
Y265748D03*
X721261Y246851D03*
X733859Y240552D03*
X727559Y259449D03*
Y265748D03*
Y253150D03*
Y240551D03*
X727560Y246851D03*
X727559Y221654D03*
Y234252D03*
X727594Y227950D03*
X696600Y241500D03*
X701500Y250564D03*
X730710Y281496D03*
X733859D03*
Y275198D03*
X730710Y272048D03*
X733858Y268897D03*
X730710Y268899D03*
X721260Y275196D03*
X733859Y278346D03*
X730708Y290944D03*
X724409D03*
X727559Y272047D03*
Y278346D03*
X784277Y243713D03*
X784253Y227953D03*
Y231103D03*
X752756Y234253D03*
Y231103D03*
Y224804D03*
Y227954D03*
X749606Y231103D03*
Y234253D03*
Y227954D03*
Y224804D03*
X737008Y256299D03*
X740158D03*
Y253149D03*
X737008D03*
X771655Y237402D03*
X737008Y243700D03*
Y246849D03*
Y249999D03*
Y265747D03*
X740158Y246849D03*
Y265747D03*
X740122Y243700D03*
X740158Y249999D03*
X752756Y221654D03*
X737008D03*
X771654Y253150D03*
X777954Y237402D03*
Y227953D03*
Y231103D03*
X765355Y265749D03*
X771654Y259449D03*
Y265749D03*
X793701Y221654D03*
X781103Y227954D03*
X784277Y246863D03*
X784267Y259426D03*
X746457Y224804D03*
X755906D03*
X737009Y227953D03*
Y234253D03*
Y231103D03*
X774804Y221655D03*
Y224804D03*
Y227954D03*
X746457D03*
X755906D03*
X746457Y231103D03*
X755906D03*
X746457Y234253D03*
X755906D03*
X759056Y253150D03*
X765355Y234253D03*
X765354Y231102D03*
X765355Y227953D03*
X765354Y246850D03*
X784277Y253162D03*
X740132Y240562D03*
X759055Y221654D03*
X765355Y224804D03*
X771654Y215355D03*
Y209056D03*
Y212205D03*
X746457Y240552D03*
X752757D03*
X759056D03*
X746421Y253149D03*
X765354Y221654D03*
X743307D03*
X762205Y215355D03*
X781103Y237402D03*
Y231103D03*
X787402Y221654D03*
X787401Y215354D03*
X746457Y246850D03*
X752720Y253149D03*
X752757Y246851D03*
X765355Y253150D03*
X759056Y246851D03*
X746433Y265761D03*
X746457Y259449D03*
X752757D03*
Y265749D03*
X765355Y259449D03*
X759056Y265749D03*
X759031Y259461D03*
X777976Y265761D03*
X784267Y256276D03*
X793701Y231103D03*
X793672Y243709D03*
X799991Y249972D03*
X799972Y262588D03*
X796822D03*
Y256289D03*
X790551Y259486D03*
X790538Y265723D03*
X793701Y237402D03*
X777976Y259461D03*
X781102Y221654D03*
X749606D03*
X762205Y212205D03*
X762173Y294089D03*
X762229Y290933D03*
X752756Y278346D03*
X774826Y268910D03*
X737009Y281496D03*
X740159D03*
X759031Y275209D03*
X765356Y272048D03*
Y275197D03*
Y278347D03*
X740158Y272046D03*
X737008D03*
Y268897D03*
X740158D03*
X746457Y272047D03*
Y275197D03*
X752757D03*
X752731Y272060D03*
X762181D03*
X759031D03*
X762206Y275197D03*
Y278347D03*
X737009Y275196D03*
X787419Y278354D03*
X737007Y290944D03*
X749579Y297254D03*
X787402Y297243D03*
X781102Y297244D03*
X771654Y297243D03*
X759058Y300414D03*
X768503Y287794D03*
X774802D03*
X787400Y287795D03*
X749607Y275197D03*
X774789Y275174D03*
X784221Y284652D03*
X777915Y281496D03*
X762189Y281514D03*
X768489Y281474D03*
X777953Y275198D03*
Y278347D03*
X784290Y272047D03*
X743306Y290944D03*
X749606Y278346D03*
X749593Y284670D03*
X799999Y290944D03*
Y284645D03*
Y278345D03*
X799974Y272058D03*
X793701Y300393D03*
X790519Y272053D03*
X790550Y287795D03*
X749605Y290944D03*
X762204Y287794D03*
X781064Y272047D03*
X784243Y278318D03*
X816079Y250464D03*
X807468Y234464D03*
X808923Y245979D03*
X806968Y253464D03*
X803300Y303700D03*
G54D18*
X64277Y502177D03*
X75399Y502179D03*
X69904Y502077D03*
X75197Y572437D03*
X67853Y558117D03*
X97926Y502300D03*
X86699D03*
X81094Y502166D03*
X89899Y558115D03*
X86750Y573864D03*
X89899D03*
X86750Y567565D03*
X89899Y564415D03*
X106272Y547370D03*
X93048Y577014D03*
X108371Y577258D03*
X99600Y673500D03*
Y678500D03*
Y683500D03*
X175197Y589764D03*
X209842Y583464D03*
X190945Y570866D03*
X206692Y592913D03*
X194094Y539370D03*
X203542Y545671D03*
X197243Y539371D03*
X206692Y555120D03*
X194093D03*
X184646D03*
X153149Y536221D03*
X165748Y558268D03*
X172048Y555120D03*
Y589764D03*
X168898D03*
Y561417D03*
Y570866D03*
X156299Y586614D03*
Y580315D03*
X159449Y567717D03*
X156299Y570866D03*
X197243Y592913D03*
X200393Y589764D03*
X187794Y586614D03*
X203542Y589764D03*
X165748Y583464D03*
X203605Y605450D03*
X200393Y596063D03*
X153149Y605513D03*
X148249Y695765D03*
X212992Y586614D03*
X222440Y605512D03*
X582219Y386612D03*
X599998Y391270D03*
X724410Y281496D03*
X768505Y243702D03*
X765353Y237402D03*
X740158Y275197D03*
G54D40*
X769266Y326534D03*
X751566Y327434D03*
X799534Y339466D03*
X760252Y353266D03*
X768384Y345134D03*
X761134Y334666D03*
X772352Y341266D03*
X780484Y333134D03*
X777434Y353566D03*
X785566Y345434D03*
X789334Y341766D03*
X797466Y333634D03*
X743434Y335566D03*
X749534Y346566D03*
X757666Y338434D03*
X807666Y331334D03*
X825646Y328193D03*
X817514Y336325D03*
G54D41*
X843419Y261781D03*
X837619Y255281D03*
X828781Y264119D03*
X836955Y245662D03*
X828117Y254500D03*
X854419Y307581D03*
X845581Y316419D03*
X858919Y292081D03*
X850081Y300919D03*
X852919Y286081D03*
X844081Y294919D03*
X849419Y267581D03*
X840581Y276419D03*
X847419Y280581D03*
X838581Y289419D03*
X834581Y270619D03*
G54D36*
X574803Y24409D03*
X763780D03*
X811024D03*
G54D31*
X346457Y57007D03*
%LPC*%
G75*
G54D42*
G01X-13131Y-65072D02*
Y-145072D01*
G01D02*
X1244069D01*
G01X-29131Y-65072D02*
Y-33072D01*
G01X-13131Y-65072D02*
X1244069D01*
G01X-13131Y-100572D02*
X1244069D01*
G01X-17131Y-49072D02*
G02I-12000J0D01*
G01X-22281D02*
G02I-6850J0D01*
G01X-13131D02*
X-45131D01*
G01X456569Y-65072D02*
Y-145072D01*
G01X594069Y-65072D02*
Y-145072D01*
G01X709069Y-65072D02*
Y-145072D01*
G01X876569Y-65072D02*
Y-145072D01*
G01X1046569Y-65072D02*
Y-145072D01*
G01X1244069Y-65072D02*
Y-145072D01*
G01X1272069Y-49072D02*
G02I-12000J0D01*
G01X1266919D02*
G02I-6850J0D01*
G01X1276069D02*
X1244069D01*
G01X1260069Y-65072D02*
Y-33072D01*
G54D43*
G01X13215Y-125739D02*
X14089Y-124864D01*
X14744Y-123406D01*
X15181Y-121363D01*
X14744Y-119614D01*
X13871Y-118447D01*
X12342Y-117572D01*
X6447D01*
Y-135072D01*
X13652D01*
X15181Y-133906D01*
X16054Y-132155D01*
X16491Y-130114D01*
X16054Y-128072D01*
X14744Y-126322D01*
X13215Y-125739D01*
X6447D01*
G01X25912Y-135072D02*
Y-123406D01*
G01Y-125739D02*
X27004Y-124572D01*
X28096Y-123697D01*
X29624Y-123406D01*
X30715Y-123697D01*
X32026Y-124572D01*
G01X41884Y-140322D02*
X43194Y-140905D01*
X44941Y-140322D01*
X46032Y-139156D01*
X46906Y-137697D01*
X48215Y-133031D01*
X51054Y-123406D01*
G01X44067D02*
X48215Y-133031D01*
G01X67462Y-124864D02*
X65934Y-123697D01*
X64624Y-123406D01*
X62877Y-123989D01*
X61567Y-125155D01*
X60694Y-127197D01*
X60475Y-129239D01*
X60694Y-131281D01*
X61567Y-133031D01*
X62877Y-134489D01*
X64624Y-135072D01*
X66152Y-134489D01*
X67462Y-133322D01*
G01X78194Y-127197D02*
X85181D01*
X84526Y-125155D01*
X83434Y-123989D01*
X81906Y-123406D01*
X80377Y-123697D01*
X79067Y-124572D01*
X78194Y-126614D01*
X77757Y-128364D01*
Y-130114D01*
X78194Y-131864D01*
X79286Y-133614D01*
X80596Y-134780D01*
X82124Y-135072D01*
X83652Y-134489D01*
X85181Y-132739D01*
G01X121272Y-119031D02*
X119962Y-118155D01*
X118434Y-117572D01*
X116687D01*
X114722Y-118447D01*
X113194Y-119905D01*
X112102Y-121656D01*
X111229Y-124572D01*
X111010Y-127197D01*
X111447Y-129822D01*
X112102Y-131572D01*
X113412Y-133322D01*
X114941Y-134489D01*
X116469Y-135072D01*
X117997D01*
X119526Y-134489D01*
X120836Y-133614D01*
X121928Y-132448D01*
G01X137899Y-135072D02*
Y-123406D01*
G01Y-125447D02*
X137026Y-124281D01*
X135715Y-123697D01*
X134187Y-123406D01*
X132659Y-123989D01*
X131349Y-125155D01*
X130475Y-126905D01*
X130039Y-129239D01*
X130475Y-131572D01*
X131349Y-133322D01*
X132659Y-134489D01*
X134187Y-135072D01*
X135715Y-134780D01*
X137026Y-133906D01*
X137899Y-132739D01*
G01X147757Y-135072D02*
Y-123406D01*
G01Y-126322D02*
X148631Y-124864D01*
X149941Y-123697D01*
X151687Y-123406D01*
X153215Y-123697D01*
X154526Y-124864D01*
X155181Y-126905D01*
Y-135072D01*
G01X164384Y-140322D02*
X165694Y-140905D01*
X167441Y-140322D01*
X168532Y-139156D01*
X169406Y-137697D01*
X170715Y-133031D01*
X173554Y-123406D01*
G01X166567D02*
X170715Y-133031D01*
G01X186469Y-135072D02*
X185159Y-134780D01*
X183849Y-133614D01*
X182975Y-131572D01*
X182539Y-129239D01*
X182975Y-126905D01*
X183849Y-124864D01*
X185159Y-123697D01*
X186469Y-123406D01*
X187779Y-123697D01*
X189089Y-124864D01*
X189962Y-126905D01*
X190181Y-129239D01*
X189962Y-131572D01*
X189089Y-133614D01*
X187779Y-134780D01*
X186469Y-135072D01*
G01X200257D02*
Y-123406D01*
G01Y-126322D02*
X201131Y-124864D01*
X202441Y-123697D01*
X204187Y-123406D01*
X205715Y-123697D01*
X207026Y-124864D01*
X207681Y-126905D01*
Y-135072D01*
G01X236349Y-117572D02*
X241589D01*
G01X238969D02*
Y-135072D01*
G01X236349D02*
X241589D01*
G01X256469D02*
X254722Y-134780D01*
X253194Y-133614D01*
X251884Y-131864D01*
X251010Y-129822D01*
X250574Y-127489D01*
Y-125155D01*
X251010Y-122822D01*
X251884Y-120780D01*
X253194Y-119031D01*
X254722Y-117864D01*
X256469Y-117572D01*
X258215Y-117864D01*
X259744Y-119031D01*
X261054Y-120780D01*
X261928Y-122822D01*
X262364Y-125155D01*
Y-127489D01*
X261928Y-129822D01*
X261054Y-131864D01*
X259744Y-133614D01*
X258215Y-134780D01*
X256469Y-135072D01*
G01X268292D02*
Y-117572D01*
X273969Y-132155D01*
X279646Y-117572D01*
Y-135072D01*
G01X307877Y-140905D02*
X305694Y-137989D01*
X304602Y-135072D01*
Y-123406D01*
X305694Y-120489D01*
X307877Y-117572D01*
G01X321010Y-123406D02*
X323631Y-135072D01*
X326469Y-123406D01*
X329307Y-135072D01*
X331928Y-123406D01*
G01X340039Y-135655D02*
X347899Y-117572D01*
G01X376349D02*
X381589D01*
G01X378969D02*
Y-135072D01*
G01X376349D02*
X381589D01*
G01X396469D02*
X394722Y-134780D01*
X393194Y-133614D01*
X391884Y-131864D01*
X391010Y-129822D01*
X390574Y-127489D01*
Y-125155D01*
X391010Y-122822D01*
X391884Y-120780D01*
X393194Y-119031D01*
X394722Y-117864D01*
X396469Y-117572D01*
X398215Y-117864D01*
X399744Y-119031D01*
X401054Y-120780D01*
X401928Y-122822D01*
X402364Y-125155D01*
Y-127489D01*
X401928Y-129822D01*
X401054Y-131864D01*
X399744Y-133614D01*
X398215Y-134780D01*
X396469Y-135072D01*
G01X418772Y-119031D02*
X417462Y-118155D01*
X415934Y-117572D01*
X414187D01*
X412222Y-118447D01*
X410694Y-119905D01*
X409602Y-121656D01*
X408729Y-124572D01*
X408510Y-127197D01*
X408947Y-129822D01*
X409602Y-131572D01*
X410912Y-133322D01*
X412441Y-134489D01*
X413969Y-135072D01*
X415497D01*
X417026Y-134489D01*
X418336Y-133614D01*
X419428Y-132448D01*
G01X432561Y-140905D02*
X434744Y-137989D01*
X435836Y-135072D01*
Y-123406D01*
X434744Y-120489D01*
X432561Y-117572D01*
G01X180792Y-90072D02*
Y-72572D01*
X186469Y-87155D01*
X192146Y-72572D01*
Y-90072D01*
G01X203969D02*
X202659Y-89780D01*
X201349Y-88614D01*
X200475Y-86572D01*
X200039Y-84239D01*
X200475Y-81905D01*
X201349Y-79864D01*
X202659Y-78697D01*
X203969Y-78406D01*
X205279Y-78697D01*
X206589Y-79864D01*
X207462Y-81905D01*
X207681Y-84239D01*
X207462Y-86572D01*
X206589Y-88614D01*
X205279Y-89780D01*
X203969Y-90072D01*
G01X225399Y-72572D02*
Y-90072D01*
G01Y-87448D02*
X224526Y-88906D01*
X223215Y-89780D01*
X221687Y-90072D01*
X219941Y-89489D01*
X218631Y-88031D01*
X217757Y-86281D01*
X217539Y-84239D01*
X217757Y-82197D01*
X218631Y-80447D01*
X219941Y-78989D01*
X221687Y-78406D01*
X223215Y-78697D01*
X224307Y-79281D01*
X225399Y-80447D01*
G01X235694Y-82197D02*
X242681D01*
X242026Y-80155D01*
X240934Y-78989D01*
X239406Y-78406D01*
X237877Y-78697D01*
X236567Y-79572D01*
X235694Y-81614D01*
X235257Y-83364D01*
Y-85114D01*
X235694Y-86864D01*
X236786Y-88614D01*
X238096Y-89780D01*
X239624Y-90072D01*
X241152Y-89489D01*
X242681Y-87739D01*
G01X256469Y-90072D02*
Y-72572D01*
G01X490269Y-135072D02*
Y-117572D01*
X487649Y-121072D01*
G01Y-135072D02*
X492889D01*
G01X503621Y-127781D02*
X505149Y-125739D01*
X506459Y-124572D01*
X508206Y-123989D01*
X509734Y-124572D01*
X510826Y-125739D01*
X511699Y-127489D01*
X511917Y-129530D01*
X511699Y-131281D01*
X510826Y-133031D01*
X509515Y-134489D01*
X507987Y-135072D01*
X506241Y-134489D01*
X504712Y-132739D01*
X503839Y-130114D01*
X503621Y-127197D01*
X504057Y-123406D01*
X504712Y-121363D01*
X505804Y-119322D01*
X507332Y-117864D01*
X508861Y-117572D01*
X510389Y-118155D01*
X511481Y-119614D01*
G01X520466Y-131572D02*
X521775Y-133614D01*
X523522Y-134780D01*
X525487Y-135072D01*
X527234Y-134780D01*
X528981Y-133322D01*
X530072Y-131572D01*
X530291Y-129822D01*
X529854Y-127781D01*
X528326Y-126322D01*
X526797Y-125739D01*
X524832D01*
G01X526797D02*
X528107Y-124864D01*
X529199Y-123406D01*
X529636Y-121656D01*
X529199Y-119905D01*
X528107Y-118447D01*
X526142Y-117572D01*
X524177Y-117864D01*
X522212Y-119031D01*
G01X542769Y-135072D02*
Y-117572D01*
X540149Y-121072D01*
G01Y-135072D02*
X545389D01*
G01X560269D02*
X561797Y-134780D01*
X563544Y-133906D01*
X564636Y-132448D01*
X565072Y-130405D01*
X564636Y-128364D01*
X563326Y-126614D01*
X561361Y-125739D01*
X559177D01*
X557867Y-125155D01*
X556775Y-123697D01*
X556339Y-121656D01*
X556994Y-119614D01*
X558522Y-118155D01*
X560269Y-117572D01*
X562015Y-118155D01*
X563544Y-119614D01*
X564199Y-121656D01*
X563762Y-123697D01*
X562671Y-125155D01*
X561361Y-125739D01*
X559177D01*
X557212Y-126614D01*
X555902Y-128364D01*
X555466Y-130405D01*
X555902Y-132448D01*
X556994Y-133906D01*
X558741Y-134780D01*
X560269Y-135072D01*
G01X477152Y-90072D02*
Y-72572D01*
X482392D01*
X484139Y-73447D01*
X485449Y-75489D01*
X485886Y-77822D01*
X485449Y-80155D01*
X484357Y-81905D01*
X482392Y-82781D01*
X477152D01*
G01X503822Y-74031D02*
X502512Y-73155D01*
X500984Y-72572D01*
X499237D01*
X497272Y-73447D01*
X495744Y-74905D01*
X494652Y-76656D01*
X493779Y-79572D01*
X493560Y-82197D01*
X493997Y-84822D01*
X494652Y-86572D01*
X495962Y-88322D01*
X497491Y-89489D01*
X499019Y-90072D01*
X500547D01*
X502076Y-89489D01*
X503386Y-88614D01*
X504478Y-87448D01*
G01X518265Y-80739D02*
X519139Y-79864D01*
X519794Y-78406D01*
X520231Y-76363D01*
X519794Y-74614D01*
X518921Y-73447D01*
X517392Y-72572D01*
X511497D01*
Y-90072D01*
X518702D01*
X520231Y-88906D01*
X521104Y-87155D01*
X521541Y-85114D01*
X521104Y-83072D01*
X519794Y-81322D01*
X518265Y-80739D01*
X511497D01*
G01X527469Y-95905D02*
X540569D01*
G01X546497Y-90072D02*
Y-72572D01*
X556541Y-90072D01*
Y-72572D01*
G01X569019Y-90072D02*
X567272Y-89780D01*
X565744Y-88614D01*
X564434Y-86864D01*
X563560Y-84822D01*
X563124Y-82489D01*
Y-80155D01*
X563560Y-77822D01*
X564434Y-75780D01*
X565744Y-74031D01*
X567272Y-72864D01*
X569019Y-72572D01*
X570765Y-72864D01*
X572294Y-74031D01*
X573604Y-75780D01*
X574478Y-77822D01*
X574914Y-80155D01*
Y-82489D01*
X574478Y-84822D01*
X573604Y-86864D01*
X572294Y-88614D01*
X570765Y-89780D01*
X569019Y-90072D01*
G01X647421Y-120489D02*
X648731Y-118739D01*
X650259Y-117864D01*
X652006Y-117572D01*
X654189Y-118155D01*
X655717Y-119614D01*
X656154Y-121363D01*
X655936Y-123114D01*
X655062Y-124572D01*
X650696Y-127489D01*
X648731Y-129530D01*
X647421Y-132448D01*
X646984Y-135072D01*
X656154D01*
G01X619860Y-72572D02*
X625319Y-90072D01*
X630778Y-72572D01*
G01X647186Y-90072D02*
X638452D01*
Y-72572D01*
X647186D01*
G01X643692Y-81030D02*
X638452D01*
G01X655952Y-90072D02*
Y-72572D01*
X661411D01*
X663157Y-73447D01*
X664249Y-74614D01*
X664686Y-76947D01*
X664249Y-79281D01*
X662939Y-80739D01*
X661411Y-81614D01*
X655952D01*
G01X661411D02*
X664686Y-90072D01*
G01X677819Y-90655D02*
X677382Y-90364D01*
Y-89780D01*
X677819Y-89489D01*
X678256Y-89780D01*
Y-90364D01*
X677819Y-90655D01*
G01X753402Y-117572D02*
Y-135072D01*
X762136D01*
G01X771121Y-120489D02*
X772431Y-118739D01*
X773959Y-117864D01*
X775706Y-117572D01*
X777889Y-118155D01*
X779417Y-119614D01*
X779854Y-121363D01*
X779636Y-123114D01*
X778762Y-124572D01*
X774396Y-127489D01*
X772431Y-129530D01*
X771121Y-132448D01*
X770684Y-135072D01*
X779854D01*
G01X794079Y-126322D02*
X798446D01*
Y-131572D01*
X797136Y-133322D01*
X795607Y-134489D01*
X793424Y-135072D01*
X791241Y-134489D01*
X789712Y-133322D01*
X788402Y-131572D01*
X787529Y-129530D01*
X787092Y-127197D01*
Y-125155D01*
X787529Y-123406D01*
X788402Y-121363D01*
X789712Y-119614D01*
X791022Y-118447D01*
X792769Y-117572D01*
X794297D01*
X796044Y-118155D01*
X797354Y-119322D01*
G01X805247Y-135072D02*
Y-117572D01*
X815291Y-135072D01*
Y-117572D01*
G01X822966Y-135072D02*
Y-117572D01*
X827332D01*
X829079Y-118447D01*
X830389Y-119614D01*
X831481Y-121363D01*
X832354Y-123406D01*
X832572Y-126322D01*
X832354Y-129239D01*
X831481Y-131281D01*
X830389Y-133031D01*
X829079Y-134197D01*
X827332Y-135072D01*
X822966D01*
G01X753402Y-72572D02*
Y-90072D01*
X762136D01*
G01X779199D02*
Y-78406D01*
G01Y-80447D02*
X778326Y-79281D01*
X777015Y-78697D01*
X775487Y-78406D01*
X773959Y-78989D01*
X772649Y-80155D01*
X771775Y-81905D01*
X771339Y-84239D01*
X771775Y-86572D01*
X772649Y-88322D01*
X773959Y-89489D01*
X775487Y-90072D01*
X777015Y-89780D01*
X778326Y-88906D01*
X779199Y-87739D01*
G01X788184Y-95322D02*
X789494Y-95905D01*
X791241Y-95322D01*
X792332Y-94156D01*
X793206Y-92697D01*
X794515Y-88031D01*
X797354Y-78406D01*
G01X790367D02*
X794515Y-88031D01*
G01X806994Y-82197D02*
X813981D01*
X813326Y-80155D01*
X812234Y-78989D01*
X810706Y-78406D01*
X809177Y-78697D01*
X807867Y-79572D01*
X806994Y-81614D01*
X806557Y-83364D01*
Y-85114D01*
X806994Y-86864D01*
X808086Y-88614D01*
X809396Y-89780D01*
X810924Y-90072D01*
X812452Y-89489D01*
X813981Y-87739D01*
G01X824712Y-90072D02*
Y-78406D01*
G01Y-80739D02*
X825804Y-79572D01*
X826896Y-78697D01*
X828424Y-78406D01*
X829515Y-78697D01*
X830826Y-79572D01*
G01X917819Y-135072D02*
X916072Y-134780D01*
X914544Y-133614D01*
X913234Y-131864D01*
X912360Y-129822D01*
X911924Y-127489D01*
Y-125155D01*
X912360Y-122822D01*
X913234Y-120780D01*
X914544Y-119031D01*
X916072Y-117864D01*
X917819Y-117572D01*
X919565Y-117864D01*
X921094Y-119031D01*
X922404Y-120780D01*
X923278Y-122822D01*
X923714Y-125155D01*
Y-127489D01*
X923278Y-129822D01*
X922404Y-131864D01*
X921094Y-133614D01*
X919565Y-134780D01*
X917819Y-135072D01*
G01X919565Y-130405D02*
X922186Y-135072D01*
G01X930516Y-117572D02*
Y-130114D01*
X931389Y-132739D01*
X933136Y-134489D01*
X935319Y-135072D01*
X937502Y-134489D01*
X939249Y-132739D01*
X940122Y-130114D01*
Y-117572D01*
G01X950199D02*
X955439D01*
G01X952819D02*
Y-135072D01*
G01X950199D02*
X955439D01*
G01X965297D02*
Y-117572D01*
X975341Y-135072D01*
Y-117572D01*
G01X992622Y-119031D02*
X991312Y-118155D01*
X989784Y-117572D01*
X988037D01*
X986072Y-118447D01*
X984544Y-119905D01*
X983452Y-121656D01*
X982579Y-124572D01*
X982360Y-127197D01*
X982797Y-129822D01*
X983452Y-131572D01*
X984762Y-133322D01*
X986291Y-134489D01*
X987819Y-135072D01*
X989347D01*
X990876Y-134489D01*
X992186Y-133614D01*
X993278Y-132448D01*
G01X1005319Y-135072D02*
Y-127197D01*
X1000952Y-117572D01*
G01X1009686D02*
X1005319Y-127197D01*
G01X895516Y-90072D02*
Y-72572D01*
X899882D01*
X901629Y-73447D01*
X902939Y-74614D01*
X904031Y-76363D01*
X904904Y-78406D01*
X905122Y-81322D01*
X904904Y-84239D01*
X904031Y-86281D01*
X902939Y-88031D01*
X901629Y-89197D01*
X899882Y-90072D01*
X895516D01*
G01X914544Y-82197D02*
X921531D01*
X920876Y-80155D01*
X919784Y-78989D01*
X918256Y-78406D01*
X916727Y-78697D01*
X915417Y-79572D01*
X914544Y-81614D01*
X914107Y-83364D01*
Y-85114D01*
X914544Y-86864D01*
X915636Y-88614D01*
X916946Y-89780D01*
X918474Y-90072D01*
X920002Y-89489D01*
X921531Y-87739D01*
G01X932044Y-88031D02*
X933136Y-89197D01*
X934664Y-90072D01*
X935974D01*
X937284Y-89489D01*
X938157Y-88614D01*
X938594Y-87448D01*
X938376Y-85697D01*
X937502Y-84822D01*
X933572Y-83072D01*
X932699Y-81030D01*
X933136Y-79572D01*
X934009Y-78697D01*
X935319Y-78406D01*
X936629Y-78697D01*
X937939Y-79572D01*
G01X952819Y-78406D02*
Y-90072D01*
G01Y-73739D02*
X952382Y-73447D01*
Y-72864D01*
X952819Y-72572D01*
X953256Y-72864D01*
Y-73447D01*
X952819Y-73739D01*
G01X967262Y-94447D02*
X968791Y-95614D01*
X970537Y-95905D01*
X972065Y-95614D01*
X973376Y-94156D01*
X974249Y-92114D01*
Y-78406D01*
G01Y-80739D02*
X973376Y-79572D01*
X972065Y-78697D01*
X970537Y-78406D01*
X968791Y-78989D01*
X967699Y-80155D01*
X966825Y-82197D01*
X966389Y-84239D01*
X966607Y-85989D01*
X967481Y-88031D01*
X968791Y-89489D01*
X970537Y-90072D01*
X971847Y-89780D01*
X973376Y-88614D01*
X974249Y-87448D01*
G01X984107Y-90072D02*
Y-78406D01*
G01Y-81322D02*
X984981Y-79864D01*
X986291Y-78697D01*
X988037Y-78406D01*
X989565Y-78697D01*
X990876Y-79864D01*
X991531Y-81905D01*
Y-90072D01*
G01X1002044Y-82197D02*
X1009031D01*
X1008376Y-80155D01*
X1007284Y-78989D01*
X1005756Y-78406D01*
X1004227Y-78697D01*
X1002917Y-79572D01*
X1002044Y-81614D01*
X1001607Y-83364D01*
Y-85114D01*
X1002044Y-86864D01*
X1003136Y-88614D01*
X1004446Y-89780D01*
X1005974Y-90072D01*
X1007502Y-89489D01*
X1009031Y-87739D01*
G01X1019762Y-90072D02*
Y-78406D01*
G01Y-80739D02*
X1020854Y-79572D01*
X1021946Y-78697D01*
X1023474Y-78406D01*
X1024565Y-78697D01*
X1025876Y-79572D01*
G01X1066519Y-117572D02*
X1064772Y-118155D01*
X1063462Y-119614D01*
X1062589Y-121363D01*
X1061934Y-123697D01*
X1061716Y-126322D01*
X1061934Y-128947D01*
X1062589Y-131281D01*
X1063462Y-133031D01*
X1064772Y-134489D01*
X1066519Y-135072D01*
X1068265Y-134489D01*
X1069576Y-133031D01*
X1070449Y-131281D01*
X1071104Y-128947D01*
X1071322Y-126322D01*
X1071104Y-123697D01*
X1070449Y-121363D01*
X1069576Y-119614D01*
X1068265Y-118155D01*
X1066519Y-117572D01*
G01X1084019Y-135072D02*
X1085547Y-134780D01*
X1087294Y-133906D01*
X1088386Y-132448D01*
X1088822Y-130405D01*
X1088386Y-128364D01*
X1087076Y-126614D01*
X1085111Y-125739D01*
X1082927D01*
X1081617Y-125155D01*
X1080525Y-123697D01*
X1080089Y-121656D01*
X1080744Y-119614D01*
X1082272Y-118155D01*
X1084019Y-117572D01*
X1085765Y-118155D01*
X1087294Y-119614D01*
X1087949Y-121656D01*
X1087512Y-123697D01*
X1086421Y-125155D01*
X1085111Y-125739D01*
X1082927D01*
X1080962Y-126614D01*
X1079652Y-128364D01*
X1079216Y-130405D01*
X1079652Y-132448D01*
X1080744Y-133906D01*
X1082491Y-134780D01*
X1084019Y-135072D01*
G01X1097589Y-135655D02*
X1105449Y-117572D01*
G01X1119019D02*
X1117272Y-118155D01*
X1115962Y-119614D01*
X1115089Y-121363D01*
X1114434Y-123697D01*
X1114216Y-126322D01*
X1114434Y-128947D01*
X1115089Y-131281D01*
X1115962Y-133031D01*
X1117272Y-134489D01*
X1119019Y-135072D01*
X1120765Y-134489D01*
X1122076Y-133031D01*
X1122949Y-131281D01*
X1123604Y-128947D01*
X1123822Y-126322D01*
X1123604Y-123697D01*
X1122949Y-121363D01*
X1122076Y-119614D01*
X1120765Y-118155D01*
X1119019Y-117572D01*
G01X1136082Y-135072D02*
X1136519Y-131281D01*
X1137174Y-128072D01*
X1138047Y-125155D01*
X1139139Y-121947D01*
X1140886Y-117572D01*
X1132152D01*
G01X1150089Y-135655D02*
X1157949Y-117572D01*
G01X1167371Y-120489D02*
X1168681Y-118739D01*
X1170209Y-117864D01*
X1171956Y-117572D01*
X1174139Y-118155D01*
X1175667Y-119614D01*
X1176104Y-121363D01*
X1175886Y-123114D01*
X1175012Y-124572D01*
X1170646Y-127489D01*
X1168681Y-129530D01*
X1167371Y-132448D01*
X1166934Y-135072D01*
X1176104D01*
G01X1189019Y-117572D02*
X1187272Y-118155D01*
X1185962Y-119614D01*
X1185089Y-121363D01*
X1184434Y-123697D01*
X1184216Y-126322D01*
X1184434Y-128947D01*
X1185089Y-131281D01*
X1185962Y-133031D01*
X1187272Y-134489D01*
X1189019Y-135072D01*
X1190765Y-134489D01*
X1192076Y-133031D01*
X1192949Y-131281D01*
X1193604Y-128947D01*
X1193822Y-126322D01*
X1193604Y-123697D01*
X1192949Y-121363D01*
X1192076Y-119614D01*
X1190765Y-118155D01*
X1189019Y-117572D01*
G01X1206519Y-135072D02*
Y-117572D01*
X1203899Y-121072D01*
G01Y-135072D02*
X1209139D01*
G01X1223582D02*
X1224019Y-131281D01*
X1224674Y-128072D01*
X1225547Y-125155D01*
X1226639Y-121947D01*
X1228386Y-117572D01*
X1219652D01*
G01X1114216Y-90072D02*
Y-72572D01*
X1118582D01*
X1120329Y-73447D01*
X1121639Y-74614D01*
X1122731Y-76363D01*
X1123604Y-78406D01*
X1123822Y-81322D01*
X1123604Y-84239D01*
X1122731Y-86281D01*
X1121639Y-88031D01*
X1120329Y-89197D01*
X1118582Y-90072D01*
X1114216D01*
G01X1140449D02*
Y-78406D01*
G01Y-80447D02*
X1139576Y-79281D01*
X1138265Y-78697D01*
X1136737Y-78406D01*
X1135209Y-78989D01*
X1133899Y-80155D01*
X1133025Y-81905D01*
X1132589Y-84239D01*
X1133025Y-86572D01*
X1133899Y-88322D01*
X1135209Y-89489D01*
X1136737Y-90072D01*
X1138265Y-89780D01*
X1139576Y-88906D01*
X1140449Y-87739D01*
G01X1154019Y-72572D02*
Y-90072D01*
G01X1150962Y-78406D02*
X1157076D01*
G01X1168244Y-82197D02*
X1175231D01*
X1174576Y-80155D01*
X1173484Y-78989D01*
X1171956Y-78406D01*
X1170427Y-78697D01*
X1169117Y-79572D01*
X1168244Y-81614D01*
X1167807Y-83364D01*
Y-85114D01*
X1168244Y-86864D01*
X1169336Y-88614D01*
X1170646Y-89780D01*
X1172174Y-90072D01*
X1173702Y-89489D01*
X1175231Y-87739D01*
M02*
